A!REFDES!COMP_REUSE_ID!COMP_SIGNAL_MODEL!COMP_NO_XNET_CONNECTION!COMP_PARENT_PPT!COMP_SYMBOL_EDITED!COMP_PARENT_PPT_PART!COMP_EMBEDDED_PLACEMENT!
J!K:/<user>/emsd/Crescent_City/baseboard_fab2/worklib/baseboard_fab2/physical/crescent_city_fab2_2v290_20151002_C_gridout2.brd!Fri Oct 02 10:48:00 2015!-30224.80!-14061.09!740148.33!322724.71!0.01!mils!BASEBOARD_FAB2!89.440157 mil!14!UP TO DATE!
S!U1M6!!74CBTLV1G125_SMLF-IC_C88177-00A!!74CBTLV1G125!!74CBTLV1G125_SMLF-IC,C88177-001!!
S!U4R1!!!!74CBTLV1G125!!74CBTLV1G125_SMLF-IC,C88177-001!!
S!U6M1!!!!74CBTLV1G125!!74CBTLV1G125_SMLF-IC,C88177-001!!
S!U7D1!!!!74CBTLV1G125!!74CBTLV1G125_SMLF-IC,C88177-001!!
S!U1M5!!!!74CBTLV1G125!!74CBTLV1G125_SMLF-IC,C88177-001!!
S!U9A5!!!!74CBTLV1G125!!74CBTLV1G125_SMLF-IC,C88177-001!!
S!U1M4!!74CBTLV1G125_SMLF-IC_C88177-00A!!74CBTLV1G125!!74CBTLV1G125_SMLF-IC,C88177-001!!
S!U1M2!!NC7SB3157_SMLF-IC_C99406-001!!NC7SB3157!!NC7SB3157_SMLF-IC,C99406-001!!
S!U1M7!!NC7SB3157_SMLF-IC_C99406-001!!NC7SB3157!!NC7SB3157_SMLF-IC,C99406-001!!
S!U2M1!!!!NC7SB3157!!NC7SB3157_SMLF-IC,C99406-001!!
S!Q1D3!15!NPN_SM-MMBT3904_IC_C52245-001!!NPN!!NPN_SM-MMBT3904,IC,C52245-001!!
S!Q1L1!!NPN_SM-MMBT3904_IC_C52245-001!!NPN!!NPN_SM-MMBT3904,IC,C52245-001!!
S!Q1L3!!NPN_SM-MMBT3904_IC_C52245-001!!NPN!!NPN_SM-MMBT3904,IC,C52245-001!!
S!Q2T1!!NPN_SM-MMBT3904_IC_C52245-001!!NPN!!NPN_SM-MMBT3904,IC,C52245-001!!
S!Q9T1!!NPN_SM-MMBT3904_IC_C52245-001!!NPN!!NPN_SM-MMBT3904,IC,C52245-001!!
S!U2T2!!TTL1G32_A_SOT-74LVC1G32_IC_E60B!!TTL1G32_A!!TTL1G32_A_SOT-74LVC1G32,IC,E60229-001!!
S!U2T3!!TTL1G32_A_SOT-74LVC1G32_IC_E60B!!TTL1G32_A!!TTL1G32_A_SOT-74LVC1G32,IC,E60229-001!!
S!U1L1!!TTL3126_QFNLF-74CBTLV3126_IC_DB!!TTL3126!!TTL3126_QFNLF-74CBTLV3126,IC,D18317-001!!
S!U1L5!!TTL3126_QFNLF-74CBTLV3126_IC_DB!!TTL3126!!TTL3126_QFNLF-74CBTLV3126,IC,D18317-001!!
S!R2L20!69!DEFAULT_RESISTOR_68100OHM_2_1!!RES!!RES_0402-63.4K,1.0%,1/16W,CHIP,G21796-327!!
S!J1B4!!!!SCONN3_D53458001!!SCONN3_D53458001_SM-EMPTY,D53458-001!!
S!EU4A3!!!!NCP3232L!!NCP3232L_SM-IC,H86355-001!!
S!EU4G1!!!!NCP3232L!!NCP3232L_SM-IC,H86355-001!!
S!EU7B1!!!!NCP3232L!!NCP3232L_SM-IC,H86355-001!!
S!EU7F1!!!!NCP3232L!!NCP3232L_SM-IC,H86355-001!!
S!J4B2!!!!SCONN120_H61426002!!SCONN120_H61426002_SM-CONN,H61426-002!!
S!J4E1!!!!SCONN120_H61426002!!SCONN120_H61426002_SM-CONN,H61426-002!!
S!J6B1!!!!SCONN120_H61426002!!SCONN120_H61426002_SM-CONN,H61426-002!!
S!J6E1!!!!SCONN120_H61426002!!SCONN120_H61426002_SM-CONN,H61426-002!!
S!U1B3!!!!ADM4073!!ADM4073_SM-EMPTY,G12194-001!!
S!U4C1!!!!ADM4073!!ADM4073_SM-EMPTY,G12194-001!!
S!C1T18!!DEFAULT_CAPACITOR_1e+06pF_2_1!!CAP!!CAP_0402-1.0UF,6.3V,10%,EMPTY,D97712-004!!
S!C8F9!!DEFAULT_CAPACITOR_1e+06pF_2_1!!CAP!!CAP_0402-1.0UF,6.3V,10%,EMPTY,D97712-004!!
S!C1T16!!DEFAULT_CAPACITOR_1e+07pF_2_1!!CAP!!CAP_0603-10UF,6.3V,20%,EMPTY,E15431-002!!
S!C8F10!!DEFAULT_CAPACITOR_1e+07pF_2_1!!CAP!!CAP_0603-10UF,6.3V,20%,EMPTY,E15431-002!!
S!C9E1!!!!CAP!!CAP_0603-22.0UF,4V,20%,EMPTY,E15431-004!!
S!C9E12!!!!CAP!!CAP_0603-22.0UF,4V,20%,EMPTY,E15431-004!!
S!FB1T1!!DEFAULT_RESISTOR_300.000000OHM_2_1!!FERRITE!!FERRITE_SMLF-300,EMPTY,693286-046!!
S!FB2T1!!DEFAULT_RESISTOR_300.000000OHM_2_1!!FERRITE!!FERRITE_SMLF-300,EMPTY,693286-046!!
S!Y9F2!!!!OSC_C!!OSC_C_SM4-24MHZ,OSC,D34520-021!!
S!J8E4!!!!SCONN64_H87568002_A!!SCONN64_H87568002_A_SMT-CONN,H87568-002!!
S!C9B8!!!!CAPP!!CAPP_7343HLF-330UF,10V,20%,POSCAP,724613-043!!
S!Q1B1!5!!!MOSFET_N!!MOSFET_N_LCC3-BSZ019N03LS,NFET,G26762-001!!
S!Q7E7!3!!!MOSFET_N!!MOSFET_N_LCC3-BSZ019N03LS,NFET,G26762-001!!
S!Q8B1!!!!MOSFET_N!!MOSFET_N_LCC3-BSZ019N03LS,NFET,G26762-001!!
S!Q8G1!!!!MOSFET_N!!MOSFET_N_LCC3-BSZ019N03LS,NFET,G26762-001!!
S!R7D15!!!!RES!!RES_0402-348,1%,1/16W,CHIP,G21796-340!!
S!C3P10!!DEFAULT_CAPACITOR_220000pF_2_1!!CAP!!CAP_0402-0.22UF,16V,10%,EMPTY,A36096-155!!
S!C3P12!!DEFAULT_CAPACITOR_220000pF_2_1!!CAP!!CAP_0402-0.22UF,16V,10%,EMPTY,A36096-155!!
S!C3P14!!DEFAULT_CAPACITOR_220000pF_2_1!!CAP!!CAP_0402-0.22UF,16V,10%,EMPTY,A36096-155!!
S!C3P16!!DEFAULT_CAPACITOR_220000pF_2_1!!CAP!!CAP_0402-0.22UF,16V,10%,EMPTY,A36096-155!!
S!C3P19!!DEFAULT_CAPACITOR_220000pF_2_1!!CAP!!CAP_0402-0.22UF,16V,10%,EMPTY,A36096-155!!
S!C3P21!!DEFAULT_CAPACITOR_220000pF_2_1!!CAP!!CAP_0402-0.22UF,16V,10%,EMPTY,A36096-155!!
S!C3P22!!DEFAULT_CAPACITOR_220000pF_2_1!!CAP!!CAP_0402-0.22UF,16V,10%,EMPTY,A36096-155!!
S!C3P24!!DEFAULT_CAPACITOR_220000pF_2_1!!CAP!!CAP_0402-0.22UF,16V,10%,EMPTY,A36096-155!!
S!C3P26!!DEFAULT_CAPACITOR_220000pF_2_1!!CAP!!CAP_0402-0.22UF,16V,10%,EMPTY,A36096-155!!
S!C3P29!!DEFAULT_CAPACITOR_220000pF_2_1!!CAP!!CAP_0402-0.22UF,16V,10%,EMPTY,A36096-155!!
S!C3P31!!DEFAULT_CAPACITOR_220000pF_2_1!!CAP!!CAP_0402-0.22UF,16V,10%,EMPTY,A36096-155!!
S!C3P33!!DEFAULT_CAPACITOR_220000pF_2_1!!CAP!!CAP_0402-0.22UF,16V,10%,EMPTY,A36096-155!!
S!C3P34!!DEFAULT_CAPACITOR_220000pF_2_1!!CAP!!CAP_0402-0.22UF,16V,10%,EMPTY,A36096-155!!
S!C3P36!!DEFAULT_CAPACITOR_220000pF_2_1!!CAP!!CAP_0402-0.22UF,16V,10%,EMPTY,A36096-155!!
S!C3P38!!DEFAULT_CAPACITOR_220000pF_2_1!!CAP!!CAP_0402-0.22UF,16V,10%,EMPTY,A36096-155!!
S!C3P41!!DEFAULT_CAPACITOR_220000pF_2_1!!CAP!!CAP_0402-0.22UF,16V,10%,EMPTY,A36096-155!!
S!J1B2!9!!!CONN6_C74770005!!CONN6_C74770005_PIP-HDR,C74770-005!!
S!J1F2!!!!CONN6_C74770005!!CONN6_C74770005_PIP-HDR,C74770-005!!
S!U7C1!!!!LBG_CORE_QAT_EXT_C!!LBG_CORE_QAT_EXT_C_BGA1-IC,TBD!!
S!J8G2!!!!CONN12_D59987001!!CONN12_D59987001_THLF-CONN,D59987-001!!
S!J7G3!!!!CONN12_D59987001!!CONN12_D59987001_THLF-CONN,D59987-001!!
S!J9G1!!!!CONN12_D59987001!!CONN12_D59987001_THLF-CONN,D59987-001!!
S!DS9F1!!!!LED!!LED_A1-RED,IC,D14725-005!!
S!R1D11!!DEFAULT_RESISTOR_100000OHM_2_1!!RES!!RES_0402-100.0K,1%,1/16W,CHIP,G21796-010!!
S!R1D15!!DEFAULT_RESISTOR_100000OHM_2_1!!RES!!RES_0402-100.0K,1%,1/16W,CHIP,G21796-010!!
S!R1D18!!DEFAULT_RESISTOR_100000OHM_2_1!!RES!!RES_0402-100.0K,1%,1/16W,CHIP,G21796-010!!
S!R1D32!3!DEFAULT_RESISTOR_100000OHM_2_1!YES!RES!!RES_0402-100.0K,1%,1/16W,CHIP,G21796-010!!
S!R1D37!2!DEFAULT_RESISTOR_100000OHM_2_1!YES!RES!!RES_0402-100.0K,1%,1/16W,CHIP,G21796-010!!
S!R1D39!5!DEFAULT_RESISTOR_100000OHM_2_1!YES!RES!!RES_0402-100.0K,1%,1/16W,CHIP,G21796-010!!
S!R1L9!!RES_0402-4.75K_1%_1/16W_CHIP_GA_4.75K!!RES!!RES_0402-100.0K,1%,1/16W,CHIP,G21796-010!!
S!R1U1!!DEFAULT_RESISTOR_100000OHM_2_1!!RES!!RES_0402-100.0K,1%,1/16W,CHIP,G21796-010!!
S!R1U2!!DEFAULT_RESISTOR_100000OHM_2_1!!RES!!RES_0402-100.0K,1%,1/16W,CHIP,G21796-010!!
S!R1U4!!DEFAULT_RESISTOR_100000OHM_2_1!!RES!!RES_0402-100.0K,1%,1/16W,CHIP,G21796-010!!
S!R1U5!!DEFAULT_RESISTOR_100000OHM_2_1!!RES!!RES_0402-100.0K,1%,1/16W,CHIP,G21796-010!!
S!R2T15!!DEFAULT_RESISTOR_100000OHM_2_1!!RES!!RES_0402-100.0K,1%,1/16W,CHIP,G21796-010!!
S!R3M8!!!!RES!!RES_0402-100.0K,1%,1/16W,CHIP,G21796-010!!
S!R3M9!!!!RES!!RES_0402-100.0K,1%,1/16W,CHIP,G21796-010!!
S!R8B4!!!!RES!!RES_0402-100.0K,1%,1/16W,CHIP,G21796-010!!
S!R9F4!!DEFAULT_RESISTOR_100000OHM_2_1!!RES!!RES_0402-100.0K,1%,1/16W,CHIP,G21796-010!!
S!R9F42!!DEFAULT_RESISTOR_100000OHM_2_1!!RES!!RES_0402-100.0K,1%,1/16W,CHIP,G21796-010!!
S!R9F43!!DEFAULT_RESISTOR_100000OHM_2_1!!RES!!RES_0402-100.0K,1%,1/16W,CHIP,G21796-010!!
S!R9F44!!DEFAULT_RESISTOR_100000OHM_2_1!!RES!!RES_0402-100.0K,1%,1/16W,CHIP,G21796-010!!
S!R9F45!!DEFAULT_RESISTOR_100000OHM_2_1!!RES!!RES_0402-100.0K,1%,1/16W,CHIP,G21796-010!!
S!R9F46!!DEFAULT_RESISTOR_100000OHM_2_1!!RES!!RES_0402-100.0K,1%,1/16W,CHIP,G21796-010!!
S!R9G26!!DEFAULT_RESISTOR_100000OHM_2_1!!RES!!RES_0402-100.0K,1%,1/16W,CHIP,G21796-010!!
S!R9P23!20!DEFAULT_RESISTOR_100000OHM_2_1!!RES!!RES_0402-100.0K,1%,1/16W,CHIP,G21796-010!!
S!R9P28!13!DEFAULT_RESISTOR_100000OHM_2_1!!RES!!RES_0402-100.0K,1%,1/16W,CHIP,G21796-010!!
S!R9P29!12!DEFAULT_RESISTOR_100000OHM_2_1!!RES!!RES_0402-100.0K,1%,1/16W,CHIP,G21796-010!!
S!R8D38!!!!RES!!RES_0402-100.0K,1%,1/16W,CHIP,G21796-010!!
S!R9P33!!!!RES!!RES_0402-100.0K,1%,1/16W,CHIP,G21796-010!!
S!CR1F5!!!!DIODE!!DIODE_SM-MBRS340T3G,EMPTY,C81983-002!!
S!EU3P1!390!!!PXE1110B!!PXE1110B_QFN-IC,H89187-001!!
S!EU4D5!353!!!PXE1110B!!PXE1110B_QFN-IC,H89187-001!!
S!EU8A1!!!!PXE1110B!!PXE1110B_QFN-IC,H89187-001!!
S!EU1B1!119!!!PXM1310B!!PXM1310B_QFN-IC,H89186-001!!
S!EU1G2!19!!!PXM1310B!!PXM1310B_QFN-IC,H89186-001!!
S!EU7A5!!!!PXM1310B!!PXM1310B_QFN-IC,H89186-001!!
S!EU7G1!82!!!PXM1310B!!PXM1310B_QFN-IC,H89186-001!!
S!R1C13!!DEFAULT_RESISTOR_19100OHM_2_1!!RES!!RES_0402-100.0K,1%,1/16W,CHIP,G21796-160!!
S!R3L12!!DEFAULT_RESISTOR_0.002OHM_2_1!!RES!!RES_0402-100.0K,1%,1/16W,CHIP,G21796-160!!
S!R3P12!398!DEFAULT_RESISTOR_0.002OHM_2_1!YES!RES!!RES_0402-100.0K,1%,1/16W,CHIP,G21796-160!!
S!R4D27!29!DEFAULT_RESISTOR_19100OHM_2_1!!RES!!RES_0402-100.0K,1%,1/16W,CHIP,G21796-160!!
S!R4D60!348!DEFAULT_RESISTOR_0.002OHM_2_1!!RES!!RES_0402-100.0K,1%,1/16W,CHIP,G21796-160!!
S!R7F34!88!DEFAULT_RESISTOR_19100OHM_2_1!!RES!!RES_0402-100.0K,1%,1/16W,CHIP,G21796-160!!
S!R8A4!!DEFAULT_RESISTOR_0.002OHM_2_1!!RES!!RES_0402-100.0K,1%,1/16W,CHIP,G21796-160!!
S!R9M8!122!DEFAULT_RESISTOR_0.002OHM_2_1!!RES!!RES_0402-100.0K,1%,1/16W,CHIP,G21796-160!!
S!R9U11!14!DEFAULT_RESISTOR_0.002OHM_2_1!!RES!!RES_0402-100.0K,1%,1/16W,CHIP,G21796-160!!
S!R1B12!!DEFAULT_RESISTOR_4020OHM_2_1!!RES!!RES_0402-3.16K,1%,1/16W,CHIP,G21796-043!!
S!R3N31!378!!!RES!!RES_0402-3.16K,1%,1/16W,CHIP,G21796-043!!
S!R4D64!384!DEFAULT_RESISTOR_2670OHM_2_1!!RES!!RES_0402-3.16K,1%,1/16W,CHIP,G21796-043!!
S!R4E2!!DEFAULT_RESISTOR_2670OHM_2_1!!RES!!RES_0402-3.16K,1%,1/16W,CHIP,G21796-043!!
S!R7A10!!DEFAULT_RESISTOR_4020OHM_2_1!!RES!!RES_0402-3.16K,1%,1/16W,CHIP,G21796-043!!
S!R9N7!!DEFAULT_RESISTOR_8060OHM_2_1!!RES!!RES_0402-3.16K,1%,1/16W,CHIP,G21796-043!!
S!R4C11!!!!RES!!RES_0402-3.16K,1%,1/16W,CHIP,G21796-043!!
S!J9A3!!!!SCONN60_C21100002!!SCONN60_C21100002_SMLF-CONN,C21100-002!!
S!U8F2!!!!W25Q128!!W25Q128_SKT16-IC,H12709-001!!
S!EU1C2!!!!PXE1610B!!PXE1610B_QFN-IC,H79206-001!!
S!EU4D4!14!!!PXE1610B!!PXE1610B_QFN-IC,H79206-001!!
S!R8D40!!!!RES!!RES_0402-3.74K,1%,1/16W,CHIP,G21796-059!!
S!J9B4!!!!SCONN10_C12536004!!SCONN10_C12536004_SMLF-CONN,C12536-004!!
S!C1A8!92!DEFAULT_CAPACITOR_470000pF_2_1!!CAP!!CAP_0402-0.220UF,16V,10%,X7R,A36096-104!!
S!C1A18!119!DEFAULT_CAPACITOR_470000pF_2_1!!CAP!!CAP_0402-0.220UF,16V,10%,X7R,A36096-104!!
S!C1C12!!DEFAULT_CAPACITOR_470000pF_2_1!!CAP!!CAP_0402-0.220UF,16V,10%,X7R,A36096-104!!
S!C1C24!!DEFAULT_CAPACITOR_100000pF_2_1!YES!CAP!!CAP_0402-0.220UF,16V,10%,X7R,A36096-104!!
S!C1D10!!DEFAULT_CAPACITOR_470000pF_2_1!YES!CAP!!CAP_0402-0.220UF,16V,10%,X7R,A36096-104!!
S!C1D20!6!DEFAULT_CAPACITOR_470000pF_2_1!YES!CAP!!CAP_0402-0.220UF,16V,10%,X7R,A36096-104!!
S!C1F26!26!DEFAULT_CAPACITOR_470000pF_2_1!!CAP!!CAP_0402-0.220UF,16V,10%,X7R,A36096-104!!
S!C1G11!7!DEFAULT_CAPACITOR_470000pF_2_1!!CAP!!CAP_0402-0.220UF,16V,10%,X7R,A36096-104!!
S!C4C8!79!DEFAULT_CAPACITOR_470000pF_2_1!!CAP!!CAP_0402-0.220UF,16V,10%,X7R,A36096-104!!
S!C4C17!65!DEFAULT_CAPACITOR_470000pF_2_1!YES!CAP!!CAP_0402-0.220UF,16V,10%,X7R,A36096-104!!
S!C4D9!!DEFAULT_CAPACITOR_100000pF_2_1!YES!CAP!!CAP_0402-0.220UF,16V,10%,X7R,A36096-104!!
S!C4D28!!DEFAULT_CAPACITOR_100000pF_2_1!YES!CAP!!CAP_0402-0.220UF,16V,10%,X7R,A36096-104!!
S!C4D50!51!DEFAULT_CAPACITOR_470000pF_2_1!YES!CAP!!CAP_0402-0.220UF,16V,10%,X7R,A36096-104!!
S!C4E17!37!DEFAULT_CAPACITOR_470000pF_2_1!YES!CAP!!CAP_0402-0.220UF,16V,10%,X7R,A36096-104!!
S!C4E18!324!DEFAULT_CAPACITOR_100000pF_2_1!!CAP!!CAP_0402-0.220UF,16V,10%,X7R,A36096-104!!
S!C3L30!!DEFAULT_CAPACITOR_100000pF_2_1!!CAP!!CAP_0402-0.220UF,16V,10%,X7R,A36096-104!!
S!C3L28!!DEFAULT_CAPACITOR_100000pF_2_1!!CAP!!CAP_0402-0.220UF,16V,10%,X7R,A36096-104!!
S!C7A12!33!DEFAULT_CAPACITOR_470000pF_2_1!!CAP!!CAP_0402-0.220UF,16V,10%,X7R,A36096-104!!
S!C7A22!20!DEFAULT_CAPACITOR_470000pF_2_1!!CAP!!CAP_0402-0.220UF,16V,10%,X7R,A36096-104!!
S!C7C14!412!DEFAULT_CAPACITOR_100000pF_2_1!!CAP!!CAP_0402-0.220UF,16V,10%,X7R,A36096-104!!
S!C7G31!71!DEFAULT_CAPACITOR_470000pF_2_1!!CAP!!CAP_0402-0.220UF,16V,10%,X7R,A36096-104!!
S!C7G38!40!DEFAULT_CAPACITOR_470000pF_2_1!!CAP!!CAP_0402-0.220UF,16V,10%,X7R,A36096-104!!
S!C1D36!!DEFAULT_CAPACITOR_470000pF_2_1!YES!CAP!!CAP_0402-0.220UF,16V,10%,X7R,A36096-104!!
S!C1E11!2!DEFAULT_CAPACITOR_470000pF_2_1!YES!CAP!!CAP_0402-0.220UF,16V,10%,X7R,A36096-104!!
S!J8A3!!!!CONN7_E82125014!!CONN7_E82125014_PIP_TH-CONN,E82125-014!!
S!J2M1!!!!CONN7_E82125014!!CONN7_E82125014_PIP_TH-EMPTY,E82125-014!!
S!EU4E2!323!!YES!IR354XX!!IR354XX_SM-IR35412,IC,H73684-001!!
S!EU7A2!16!!YES!IR354XX!!IR354XX_SM-IR35412,IC,H73684-001!!
S!EU7A3!!!YES!IR354XX!!IR354XX_SM-IR35412,IC,H73684-001!!
S!EU7C1!391!!YES!IR354XX!!IR354XX_SM-IR35412,IC,H73684-001!!
S!EU1C1!!!!IR354XX!!IR354XX_SM-IR35412,IC,H73684-001!!
S!EU4C1!!!!IR354XX!!IR354XX_SM-IR35412,IC,H73684-001!!
S!R5D6!!!!RES!!RES_0402-10.0,1%,1/16W,EMPTY,G21796-066!!
S!R3D32!!!!RES!!RES_0402-10.0,1%,1/16W,EMPTY,G21796-066!!
S!R4C13!!!!RES!!RES_0402-68.1K,1%,1/16W,EMPTY,G21796-187!!
S!R4E19!!!!RES!!RES_0402-68.1K,1%,1/16W,EMPTY,G21796-187!!
S!R4E22!!!!RES!!RES_0402-68.1K,1%,1/16W,EMPTY,G21796-187!!
S!R4D72!!!!RES!!RES_0402-68.1K,1%,1/16W,EMPTY,G21796-187!!
S!R4D71!!!!RES!!RES_0402-68.1K,1%,1/16W,EMPTY,G21796-187!!
S!R4D68!!!!RES!!RES_0402-68.1K,1%,1/16W,EMPTY,G21796-187!!
S!R7C25!!!!RES!!RES_0402-68.1K,1%,1/16W,EMPTY,G21796-187!!
S!R4E21!!!!RES!!RES_0402-68.1K,1%,1/16W,EMPTY,G21796-187!!
S!R7G25!!!!RES!!RES_0402-68.1K,1%,1/16W,EMPTY,G21796-187!!
S!R7G30!!!!RES!!RES_0402-68.1K,1%,1/16W,EMPTY,G21796-187!!
S!R7A20!!!!RES!!RES_0402-68.1K,1%,1/16W,EMPTY,G21796-187!!
S!R7A21!!!!RES!!RES_0402-68.1K,1%,1/16W,EMPTY,G21796-187!!
S!R1G26!!!!RES!!RES_0402-68.1K,1%,1/16W,EMPTY,G21796-187!!
S!R1G25!!!!RES!!RES_0402-68.1K,1%,1/16W,EMPTY,G21796-187!!
S!R1A2!!!!RES!!RES_0402-68.1K,1%,1/16W,EMPTY,G21796-187!!
S!R1A3!!!!RES!!RES_0402-68.1K,1%,1/16W,EMPTY,G21796-187!!
S!R3L15!!!!RES!!RES_0402-68.1K,1%,1/16W,EMPTY,G21796-187!!
S!R3L14!!!!RES!!RES_0402-68.1K,1%,1/16W,EMPTY,G21796-187!!
S!R1E13!!!!RES!!RES_0402-68.1K,1%,1/16W,EMPTY,G21796-187!!
S!R1E14!!!!RES!!RES_0402-68.1K,1%,1/16W,EMPTY,G21796-187!!
S!R1D55!5!!!RES!!RES_0402-68.1K,1%,1/16W,EMPTY,G21796-187!!
S!R1D54!!!!RES!!RES_0402-68.1K,1%,1/16W,EMPTY,G21796-187!!
S!R1D52!!!!RES!!RES_0402-68.1K,1%,1/16W,EMPTY,G21796-187!!
S!R1C37!!!!RES!!RES_0402-68.1K,1%,1/16W,EMPTY,G21796-187!!
S!R5P1!!!!RES!!RES_0603-100.0K,1%,1/10W,CHIP,G22026-050!!
S!RT8P1!!!!RES!!RES_0603-100.0K,1%,1/10W,CHIP,G22026-050!!
S!EU1A1!69!!YES!IR354XX!!IR354XX_SM-IR35411,IC,H73688-001!!
S!EU1A2!79!!YES!IR354XX!!IR354XX_SM-IR35411,IC,H73688-001!!
S!EU1F1!22!!!IR354XX!!IR354XX_SM-IR35411,IC,H73688-001!!
S!EU1G1!15!!YES!IR354XX!!IR354XX_SM-IR35411,IC,H73688-001!!
S!EU7A1!28!!YES!IR354XX!!IR354XX_SM-IR35411,IC,H73688-001!!
S!EU7A4!8!!YES!IR354XX!!IR354XX_SM-IR35411,IC,H73688-001!!
S!EU7G2!12!!YES!IR354XX!!IR354XX_SM-IR35411,IC,H73688-001!!
S!EU7G3!10!!YES!IR354XX!!IR354XX_SM-IR35411,IC,H73688-001!!
S!EU4D6!!!!IR354XX!!IR354XX_SM-IR35411,IC,H73688-001!!
S!EU1C3!!!!IR354XX!!IR354XX_SM-IR35411,IC,H73688-001!!
S!EU1D1!!!!IR354XX!!IR354XX_SM-IR35411,IC,H73688-001!!
S!EU4D3!!!!IR354XX!!IR354XX_SM-IR35411,IC,H73688-001!!
S!EU4D1!!!!IR354XX!!IR354XX_SM-IR35411,IC,H73688-001!!
S!EU4C2!!!!IR354XX!!IR354XX_SM-IR35411,IC,H73688-001!!
S!EU4E1!30!!!IR354XX!!IR354XX_SM-IR35411,IC,H73688-001!!
S!EU1D3!12!!!IR354XX!!IR354XX_SM-IR35411,IC,H73688-001!!
S!EU1D4!!!!IR354XX!!IR354XX_SM-IR35411,IC,H73688-001!!
S!EU1E2!1!!!IR354XX!!IR354XX_SM-IR35411,IC,H73688-001!!
S!Y3F1!!!!OSC_C!!OSC_C_6P10-156.25MHZ,OSC,G63831-004!!
S!Y6F1!!!!OSC_C!!OSC_C_6P10-156.25MHZ,OSC,G63831-004!!
S!U8E1!!!!TTL08!!TTL08_QFN15-74LVC08A,IC,D90404-001!!
S!U1E2!!!!TTL1G08!!TTL1G08_SOTLF-NC7SZ08,IC,D10321-001!!
S!U7E2!1!!!TTL1G08!!TTL1G08_SOTLF-NC7SZ08,IC,D10321-001!!
S!U7E3!!!!TTL1G08!!TTL1G08_SOTLF-NC7SZ08,IC,D10321-001!!
S!U1M1!!!!TTL1G08!!TTL1G08_SOTLF-NC7SZ08,IC,D10321-001!!
S!U1D1!!!!TTL1G126_A!!TTL1G126_A_SOT-74HC1G126,IC,A79322-001!!
S!U1R2!!!!TTL1G126_A!!TTL1G126_A_SOT-74HC1G126,IC,A79322-001!!
S!U8D5!!!!TTL1G126_A!!TTL1G126_A_SOT-74HC1G126,IC,A79322-001!!
S!U8E3!!!!TTL1G126_A!!TTL1G126_A_SOT-74HC1G126,IC,A79322-001!!
S!U8E4!!!!TTL1G126_A!!TTL1G126_A_SOT-74HC1G126,IC,A79322-001!!
S!R7D13!!DEFAULT_RESISTOR_10000OHM_2_1!!RES!!RES_0402-8.2K,1%,1/16W,EMPTY,G21796-345!!
S!TC1!!!!TP3_PPROBEB!!TP3_PPROBEB_SM-EMPTY,NA!!
S!TC3!!!!TP3_PPROBEB!!TP3_PPROBEB_SM-EMPTY,NA!!
S!TC4!!!!TP3_PPROBEB!!TP3_PPROBEB_SM-EMPTY,NA!!
S!TC7!!!!TP3_PPROBEB!!TP3_PPROBEB_SM-EMPTY,NA!!
S!TC8!!!!TP3_PPROBEB!!TP3_PPROBEB_SM-EMPTY,NA!!
S!TC10!!!!TP3_PPROBEB!!TP3_PPROBEB_SM-EMPTY,NA!!
S!TC11!!!!TP3_PPROBEB!!TP3_PPROBEB_SM-EMPTY,NA!!
S!TC19!!!!TP3_PPROBEB!!TP3_PPROBEB_SM-EMPTY,NA!!
S!TC20!!!!TP3_PPROBEB!!TP3_PPROBEB_SM-EMPTY,NA!!
S!R1R15!!!!RES!!RES_0603-0,5.0%,1/10W,CHIP,G22178-002!!
S!R1T32!!!!RES!!RES_0603-0,5.0%,1/10W,CHIP,G22178-002!!
S!R1T34!!!!RES!!RES_0603-0,5.0%,1/10W,CHIP,G22178-002!!
S!R1T33!!!!RES!!RES_0603-0,5.0%,1/10W,EMPTY,G22178-002!!
S!JA9G1!!!!CONN17_H71061002!!CONN17_H71061002_PIP1-CONN,H71061-002!!
S!U1L3!!!!ADM809!!ADM809_SMLF-IC,D23047-001!!
S!U8E2!!!!ADM809!!ADM809_SMLF-IC,D23047-001!!
S!U1B2!!!!PCA9517!!PCA9517_SM-IC,G77073-001!!
S!U3B1!!!!PCA9617!!PCA9617_SSOP-IC,G81764-001!!
S!U4G1!!!!PCA9617!!PCA9617_SSOP-IC,G81764-001!!
S!U6F1!7!!!PCA9617!!PCA9617_SSOP-IC,G81764-001!!
S!U7E1!!!!PCA9617!!PCA9617_SSOP-IC,G81764-001!!
S!U2T1!!!!PI3B3257A!!PI3B3257A_TSSOPLF-IC,E16801-001!!
S!U8F1!!!!PI3B3257A!!PI3B3257A_TSSOPLF-IC,E16801-001!!
S!R4U4!!!!RES!!RES_0402-33.0K,5%,1/16W,CHIP,G21497-023!!
S!J1F1!!!!CONN76_H22707001!!CONN76_H22707001_THMT1-CONN,H22707-001!!
S!J1C1!!!!CONN76_H22707001!!CONN76_H22707001_THMT1-CONN,H22707-001!!
S!R2L25!!!!RES!!RES_0402-100.0K,1%,1/16W,EMPTY,G21796-010!!
S!R2L26!!!!RES!!RES_0402-100.0K,1%,1/16W,EMPTY,G21796-010!!
S!R3P21!!!!RES!!RES_0402-100.0K,1%,1/16W,EMPTY,G21796-010!!
S!R6P40!!!!RES!!RES_0402-100.0K,1%,1/16W,EMPTY,G21796-010!!
S!R7F20!!!!RES!!RES_0402-100.0K,1%,1/16W,EMPTY,G21796-010!!
S!R3M5!!!!RES!!RES_0402-100.0K,1%,1/16W,EMPTY,G21796-010!!
S!R9U8!!!!RES!!RES_0402-100.0K,1%,1/16W,EMPTY,G21796-010!!
S!R9M5!!!!RES!!RES_0402-100.0K,1%,1/16W,EMPTY,G21796-010!!
S!R8A7!!!!RES!!RES_0402-100.0K,1%,1/16W,EMPTY,G21796-010!!
S!R8E40!!!!RES!!RES_0402-100.0K,1%,1/16W,EMPTY,G21796-010!!
S!R2N17!!!!RES!!RES_0402-2.7K,1%,1/16W,EMPTY,G21796-344!!
S!R1U21!!!!RES!!RES_0402-2.7K,1%,1/16W,EMPTY,G21796-344!!
S!R1U22!!!!RES!!RES_0402-2.7K,1%,1/16W,EMPTY,G21796-344!!
S!R1T5!!!!RES!!RES_0402-2.7K,1%,1/16W,EMPTY,G21796-344!!
S!R1T6!!!!RES!!RES_0402-2.7K,1%,1/16W,EMPTY,G21796-344!!
S!R9A2!!RES_0402-33_1.0%_1/16W_EMPTY_GA_NA!!RES!!RES_0402-33.2,1%,1/16W,EMPTY,G21796-074!!
S!C9F20!!DEFAULT_CAPACITOR_22.000000pF_2_1!!CAP!!CAP_0402LF-12.0PF,50V,5%,COG,A36095-043!!
S!C9F21!!DEFAULT_CAPACITOR_33.000000pF_2_1!!CAP!!CAP_0402LF-12.0PF,50V,5%,COG,A36095-043!!
S!J1B3!!!!CONN3_C95678002!!CONN3_C95678002_PIP-CONN,C95678-002!!
S!J9B2!!!!CONN3_C95678002!!CONN3_C95678002_PIP-CONN,C95678-002!!
S!J8C1!!!!CONN3_C95678002!!CONN3_C95678002_PIP-CONN,C95678-002!!
S!J8D4!!!!CONN3_C95678002!!CONN3_C95678002_PIP-CONN,C95678-002!!
S!U9E1!!!!M25PE16!!M25PE16_SM-IC,H77797-001!!
S!Q8D1!!!!NPN_DUAL!!NPN_DUAL_SSOPLF-MBT3904,XSTR,C52264-001!!
S!U5D1!!!!SKX_EXT_B!!SKX_EXT_B_BGA1-IC,TBD!!
S!U2D1!!!!SKX_EXT_B!!SKX_EXT_B_BGA1-IC,TBD!!
S!EU2T1!!!!SLG55021!!SLG55021_SM-IC,G56246-001!!
S!EU7E1!2!!!SLG55021!!SLG55021_SM-IC,G56246-001!!
S!EU8B1!!!!SLG55021!!SLG55021_SM-IC,G56246-001!!
S!EU9M1!6!!!SLG55021!!SLG55021_SM-IC,G56246-001!!
S!Y9E1!!!!CRYSTAL!!CRYSTAL_2013-25.000MHZ,IC,D71700-057!!
S!R3P48!!DEFAULT_RESISTOR_100000OHM_2_1!!RES!!RES_0402-90.9K,1%,1/16W,CHIP,G21796-058!!
S!R1D13!!DEFAULT_RESISTOR_88700OHM_2_1!YES!RES!!RES_0402-90.9K,1%,1/16W,CHIP,G21796-058!!
S!L7C2!431!DEFAULT_INDUCTOR_300.000000nH_2_1!!INDUCTOR!!INDUCTOR_SM-150NH,IND,D92183-021!!
S!L4E2!341!DEFAULT_INDUCTOR_300.000000nH_2_1!!INDUCTOR!!INDUCTOR_SM-150NH,IND,D92183-021!!
S!C2P10!!!!CAP!!CAP_1206LF-22UF,16V,10%,X6S,D38464-005!!
S!C8E10!!DEFAULT_CAPACITOR_2.2e+07pF_2_1!!CAP!!CAP_1206LF-22UF,16V,10%,X6S,D38464-005!!
S!C7E11!36!DEFAULT_CAPACITOR_2.2e+07pF_2_1!!CAP!!CAP_1206LF-22UF,16V,10%,X6S,D38464-005!!
S!J2L1!!!!CONN4_H73295001!!CONN4_H73295001_PIP-EMPTY,H73295-001!!
S!J4G1!6!!!SCONN288_H44441004!!SCONN288_H44441004_PIP-SCONN,H44441-004!!
S!J4G2!5!!!SCONN288_H44441004!!SCONN288_H44441004_PIP-SCONN,H44441-004!!
S!J4G3!4!!!SCONN288_H44441004!!SCONN288_H44441004_PIP-SCONN,H44441-004!!
S!J4B1!!!!SCONN288_H44441004!!SCONN288_H44441004_PIP-SCONN,H44441-004!!
S!J4A2!!!!SCONN288_H44441004!!SCONN288_H44441004_PIP-SCONN,H44441-004!!
S!J4A1!!!!SCONN288_H44441004!!SCONN288_H44441004_PIP-SCONN,H44441-004!!
S!J1G1!!!!SCONN288_H44441004!!SCONN288_H44441004_PIP-SCONN,H44441-004!!
S!J1G2!!!!SCONN288_H44441004!!SCONN288_H44441004_PIP-SCONN,H44441-004!!
S!J1G3!!!!SCONN288_H44441004!!SCONN288_H44441004_PIP-SCONN,H44441-004!!
S!J1B1!!!!SCONN288_H44441004!!SCONN288_H44441004_PIP-SCONN,H44441-004!!
S!J1A2!!!!SCONN288_H44441004!!SCONN288_H44441004_PIP-SCONN,H44441-004!!
S!J1A1!!!!SCONN288_H44441004!!SCONN288_H44441004_PIP-SCONN,H44441-004!!
S!R2U12!!RES_0402-20.0_1%_1/16W_CHIP_G21A_0.0!!RES!!RES_0402-20.0,1%,1/16W,EMPTY,G21796-173!!
S!R2U8!!RES_0402-20.0_1%_1/16W_CHIP_G21A_0.0!!RES!!RES_0402-20.0,1%,1/16W,EMPTY,G21796-173!!
S!R2U35!!RES_0402-0.0_5%_1/16W_EMPTY_G2A_NA!!RES!!RES_0402-20.0,1%,1/16W,EMPTY,G21796-173!!
S!R2U36!!RES_0402-0.0_5%_1/16W_EMPTY_G2A_NA!!RES!!RES_0402-20.0,1%,1/16W,EMPTY,G21796-173!!
S!J6T1!3!!!SCONN288_H44441003!!SCONN288_H44441003_PIP-SCONN,H44441-003!!
S!J6U1!2!!!SCONN288_H44441003!!SCONN288_H44441003_PIP-SCONN,H44441-003!!
S!J6U2!1!!!SCONN288_H44441003!!SCONN288_H44441003_PIP-SCONN,H44441-003!!
S!J6M1!!!!SCONN288_H44441003!!SCONN288_H44441003_PIP-SCONN,H44441-003!!
S!J6L2!!!!SCONN288_H44441003!!SCONN288_H44441003_PIP-SCONN,H44441-003!!
S!J6L1!!!!SCONN288_H44441003!!SCONN288_H44441003_PIP-SCONN,H44441-003!!
S!J9T1!!!!SCONN288_H44441003!!SCONN288_H44441003_PIP-SCONN,H44441-003!!
S!J9U1!!!!SCONN288_H44441003!!SCONN288_H44441003_PIP-SCONN,H44441-003!!
S!J9U2!!!!SCONN288_H44441003!!SCONN288_H44441003_PIP-SCONN,H44441-003!!
S!J9M1!!!!SCONN288_H44441003!!SCONN288_H44441003_PIP-SCONN,H44441-003!!
S!J9L2!!!!SCONN288_H44441003!!SCONN288_H44441003_PIP-SCONN,H44441-003!!
S!J9L1!!!!SCONN288_H44441003!!SCONN288_H44441003_PIP-SCONN,H44441-003!!
S!J8E3!!!!SCONN80_E67482007!!SCONN80_E67482007_SM-CONN,E67482-007!!
S!R3N29!!!!RES!!RES_0402-16K,1.0%,1/16W,CHIP,G21796-317!!
S!R1D34!!DEFAULT_RESISTOR_22100OHM_2_1!!RES!!RES_0402-16K,1.0%,1/16W,CHIP,G21796-317!!
S!R1G22!!DEFAULT_RESISTOR_3160OHM_2_1!!RES!!RES_0402-5.36K,1.0%,1/16W,CHIP,G21796-297!!
S!R1B15!!DEFAULT_RESISTOR_3160OHM_2_1!!RES!!RES_0402-5.36K,1.0%,1/16W,CHIP,G21796-297!!
S!J9B3!1!!!SCONN120_A28699018!!SCONN120_A28699018_SM-SCONN,A28699-018!!
S!Q9A1!!!!NPN_DUAL!!NPN_DUAL_SSOPLF-MBT3904,EMPTY,C52264-001!!
S!CR1E1!!!!DIODE!!DIODE_SM-SDMK0340L,EMPTY,H71799-001!!
S!CR1B1!5!!!DIODE!!DIODE_SM-SDMK0340L,EMPTY,H71799-001!!
S!RM8D1!!!!STANDOFF!!STANDOFF_TH1-SO,H72821-001!!
S!J8A4!!!!CONN4_H73295001!!CONN4_H73295001_PIP-CONN,H73295-001!!
S!CR1F2!!!!DIODE!!DIODE_SM-SDMK0340L,IC,H71799-001!!
S!CR1B3!!!!DIODE!!DIODE_SM-SDMK0340L,IC,H71799-001!!
S!CR1F1!!!!DIODE!!DIODE_SM-SDMK0340L,IC,H71799-001!!
S!CR1B2!6!!!DIODE!!DIODE_SM-SDMK0340L,IC,H71799-001!!
S!CR1F4!!!!DIODE!!DIODE_SM-SDMK0340L,IC,H71799-001!!
S!CR1F3!!!!DIODE!!DIODE_SM-SDMK0340L,IC,H71799-001!!
S!R6P32!18!!!RES!!RES_0402-2.0K,1%,1/16W,EMPTY,G21796-001!!
S!R6P37!17!!!RES!!RES_0402-2.0K,1%,1/16W,EMPTY,G21796-001!!
S!R1D16!!DEFAULT_RESISTOR_66500OHM_2_1!YES!RES!!RES_0402-69.8K,1%,1/16W,CHIP,G21796-007!!
S!R1D43!4!DEFAULT_RESISTOR_7500OHM_2_1!!RES!!RES_0402-7.5K,1%,1/16W,CHIP,G21796-177!!
S!R1D14!!DEFAULT_RESISTOR_5900OHM_2_1!!RES!!RES_0402-105.0K,1%,1/16W,CHIP,G21796-099!!
S!R9A6!!RES_0402-0.0_5%_1/16W_EMPTY_G2A_NA!!RES!!RES_0402-20.0K,1%,1/16W,EMPTY,G21796-040!!
S!R1L37!!DEFAULT_RESISTOR_332OHM_2_1!!RES!!RES_0402-301.0,1%,1/16W,CHIP,G21796-076!!
S!C1E2!!DEFAULT_CAPACITOR_68000pF_2_1!!CAP!!CAP_1206-0.068UF,50V,20%,X7R,108427-047!!
S!J7G2!!!!CONN8_C77962004!!CONN8_C77962004_PIP-CONN,C77962-004!!
S!C6L8!!DEFAULT_CAPACITOR_2.2e+08pF_2_1!!CAPP!!CAPP_7343-220UF,4V,20%,POSCAP,724613-067!!
S!C4T3!!DEFAULT_CAPACITOR_2.2e+08pF_2_1!!CAPP!!CAPP_7343-220UF,4V,20%,POSCAP,724613-067!!
S!C4M1!!DEFAULT_CAPACITOR_2.2e+08pF_2_1!!CAPP!!CAPP_7343-220UF,4V,20%,POSCAP,724613-067!!
S!C4F11!!DEFAULT_CAPACITOR_2.2e+08pF_2_1!!CAPP!!CAPP_7343-220UF,4V,20%,POSCAP,724613-067!!
S!C3F1!!!!CAP!!CAP_0603-47UF,4V,20%,X5R,602433-106!!
S!C4F2!!!!CAP!!CAP_0603-47UF,4V,20%,X5R,602433-106!!
S!C3T2!!!!CAP!!CAP_0603-47UF,4V,20%,X5R,602433-106!!
S!C3T1!!DEFAULT_CAPACITOR_4.7e+08pF_2_1!!CAP!!CAP_0603-47UF,4V,20%,X5R,602433-106!!
S!C5T1!!DEFAULT_CAPACITOR_1e+07pF_2_1!!CAP!!CAP_0603-47UF,4V,20%,X5R,602433-106!!
S!C5T4!166!DEFAULT_CAPACITOR_1e+07pF_2_1!!CAP!!CAP_0603-47UF,4V,20%,X5R,602433-106!!
S!C5T13!167!DEFAULT_CAPACITOR_1e+07pF_2_1!!CAP!!CAP_0603-47UF,4V,20%,X5R,602433-106!!
S!C5U11!168!DEFAULT_CAPACITOR_1e+07pF_2_1!!CAP!!CAP_0603-47UF,4V,20%,X5R,602433-106!!
S!C5T2!169!DEFAULT_CAPACITOR_1e+07pF_2_1!!CAP!!CAP_0603-47UF,4V,20%,X5R,602433-106!!
S!C2G15!!DEFAULT_CAPACITOR_1e+07pF_2_1!!CAP!!CAP_0603-47UF,4V,20%,X5R,602433-106!!
S!C2F1!!DEFAULT_CAPACITOR_1e+07pF_2_1!!CAP!!CAP_0603-47UF,4V,20%,X5R,602433-106!!
S!C8T1!!DEFAULT_CAPACITOR_1e+07pF_2_1!!CAP!!CAP_0603-47UF,4V,20%,X5R,602433-106!!
S!C8U9!!DEFAULT_CAPACITOR_1e+07pF_2_1!!CAP!!CAP_0603-47UF,4V,20%,X5R,602433-106!!
S!C8T11!!DEFAULT_CAPACITOR_1e+07pF_2_1!!CAP!!CAP_0603-47UF,4V,20%,X5R,602433-106!!
S!C7M5!48!DEFAULT_CAPACITOR_1e+07pF_2_1!!CAP!!CAP_0603-47UF,4V,20%,X5R,602433-106!!
S!C8M10!59!DEFAULT_CAPACITOR_1e+07pF_2_1!!CAP!!CAP_0603-47UF,4V,20%,X5R,602433-106!!
S!C2B2!58!DEFAULT_CAPACITOR_1e+07pF_2_1!!CAP!!CAP_0603-47UF,4V,20%,X5R,602433-106!!
S!C8M9!57!DEFAULT_CAPACITOR_1e+07pF_2_1!!CAP!!CAP_0603-47UF,4V,20%,X5R,602433-106!!
S!C8M2!56!DEFAULT_CAPACITOR_1e+07pF_2_1!!CAP!!CAP_0603-47UF,4V,20%,X5R,602433-106!!
S!C5M3!96!DEFAULT_CAPACITOR_1e+07pF_2_1!!CAP!!CAP_0603-47UF,4V,20%,X5R,602433-106!!
S!C5M11!!DEFAULT_CAPACITOR_1e+07pF_2_1!!CAP!!CAP_0603-47UF,4V,20%,X5R,602433-106!!
S!C5U16!!DEFAULT_CAPACITOR_1e+07pF_2_1!!CAP!!CAP_0603-47UF,4V,20%,X5R,602433-106!!
S!C5U12!!DEFAULT_CAPACITOR_1e+07pF_2_1!!CAP!!CAP_0603-47UF,4V,20%,X5R,602433-106!!
S!C5T3!!DEFAULT_CAPACITOR_1e+07pF_2_1!!CAP!!CAP_0603-47UF,4V,20%,X5R,602433-106!!
S!C5L4!!DEFAULT_CAPACITOR_1e+07pF_2_1!!CAP!!CAP_0603-47UF,4V,20%,X5R,602433-106!!
S!C5M13!!DEFAULT_CAPACITOR_1e+07pF_2_1!!CAP!!CAP_0603-47UF,4V,20%,X5R,602433-106!!
S!C5L5!!DEFAULT_CAPACITOR_1e+07pF_2_1!!CAP!!CAP_0603-47UF,4V,20%,X5R,602433-106!!
S!C2F2!!DEFAULT_CAPACITOR_1e+07pF_2_1!!CAP!!CAP_0603-47UF,4V,20%,X5R,602433-106!!
S!C8T3!!DEFAULT_CAPACITOR_1e+07pF_2_1!!CAP!!CAP_0603-47UF,4V,20%,X5R,602433-106!!
S!C8U10!!DEFAULT_CAPACITOR_1e+07pF_2_1!!CAP!!CAP_0603-47UF,4V,20%,X5R,602433-106!!
S!C8M12!!DEFAULT_CAPACITOR_1e+07pF_2_1!!CAP!!CAP_0603-47UF,4V,20%,X5R,602433-106!!
S!C8L3!!DEFAULT_CAPACITOR_1e+07pF_2_1!!CAP!!CAP_0603-47UF,4V,20%,X5R,602433-106!!
S!C8L4!!DEFAULT_CAPACITOR_1e+07pF_2_1!!CAP!!CAP_0603-47UF,4V,20%,X5R,602433-106!!
S!C4M5!106!DEFAULT_CAPACITOR_1e+07pF_2_1!!CAP!!CAP_0603-47UF,4V,20%,X5R,602433-106!!
S!C5M9!107!DEFAULT_CAPACITOR_1e+07pF_2_1!!CAP!!CAP_0603-47UF,4V,20%,X5R,602433-106!!
S!C5M10!108!DEFAULT_CAPACITOR_1e+07pF_2_1!!CAP!!CAP_0603-47UF,4V,20%,X5R,602433-106!!
S!C5F2!!DEFAULT_CAPACITOR_1e+07pF_2_1!!CAP!!CAP_0603-47UF,4V,20%,X5R,602433-106!!
S!C5F1!!DEFAULT_CAPACITOR_1e+07pF_2_1!!CAP!!CAP_0603-47UF,4V,20%,X5R,602433-106!!
S!C5G10!!DEFAULT_CAPACITOR_1e+07pF_2_1!!CAP!!CAP_0603-47UF,4V,20%,X5R,602433-106!!
S!C5L15!!DEFAULT_CAPACITOR_1e+07pF_2_1!!CAP!!CAP_0603-47UF,4V,20%,X5R,602433-106!!
S!C5B2!!DEFAULT_CAPACITOR_1e+07pF_2_1!!CAP!!CAP_0603-47UF,4V,20%,X5R,602433-106!!
S!C5A5!!DEFAULT_CAPACITOR_1e+07pF_2_1!!CAP!!CAP_0603-47UF,4V,20%,X5R,602433-106!!
S!C5B1!!DEFAULT_CAPACITOR_1e+07pF_2_1!!CAP!!CAP_0603-47UF,4V,20%,X5R,602433-106!!
S!C8U13!!DEFAULT_CAPACITOR_1e+07pF_2_1!!CAP!!CAP_0603-47UF,4V,20%,X5R,602433-106!!
S!C8T4!!DEFAULT_CAPACITOR_1e+07pF_2_1!!CAP!!CAP_0603-47UF,4V,20%,X5R,602433-106!!
S!C2G8!!DEFAULT_CAPACITOR_1e+07pF_2_1!!CAP!!CAP_0603-47UF,4V,20%,X5R,602433-106!!
S!C8T2!!DEFAULT_CAPACITOR_1e+07pF_2_1!!CAP!!CAP_0603-47UF,4V,20%,X5R,602433-106!!
S!C8L12!!DEFAULT_CAPACITOR_1e+07pF_2_1!!CAP!!CAP_0603-47UF,4V,20%,X5R,602433-106!!
S!C8M8!!DEFAULT_CAPACITOR_1e+07pF_2_1!!CAP!!CAP_0603-47UF,4V,20%,X5R,602433-106!!
S!C2A5!!DEFAULT_CAPACITOR_1e+07pF_2_1!!CAP!!CAP_0603-47UF,4V,20%,X5R,602433-106!!
S!C2B1!!DEFAULT_CAPACITOR_1e+07pF_2_1!!CAP!!CAP_0603-47UF,4V,20%,X5R,602433-106!!
S!C5G19!!DEFAULT_CAPACITOR_1e+07pF_2_1!!CAP!!CAP_0603-47UF,4V,20%,X5R,602433-106!!
S!C4F6!!DEFAULT_CAPACITOR_4.7e+08pF_2_1!!CAPP!!CAPP_4040LF-470UF,16V,20%,ALUM,A93539-036!!
S!C4B13!!DEFAULT_CAPACITOR_4.7e+08pF_2_1!!CAPP!!CAPP_4040LF-470UF,16V,20%,ALUM,A93539-036!!
S!C1B14!!DEFAULT_CAPACITOR_4.7e+08pF_2_1!!CAPP!!CAPP_4040LF-470UF,16V,20%,ALUM,A93539-036!!
S!C1F7!!DEFAULT_CAPACITOR_4.7e+08pF_2_1!!CAPP!!CAPP_4040LF-470UF,16V,20%,ALUM,A93539-036!!
S!F9B1!!!!FUSE!!FUSE_SM-IC,C94311-016!!
S!F8B1!!!!FUSE!!FUSE_SMLF-IC,C94311-006!!
S!R9F20!!DEFAULT_RESISTOR_10000OHM_2_1!!RES!!RES_0402-348,1%,1/16W,EMPTY,G21796-340!!
S!J9A2!!!!CONN14_H54902001!!CONN14_H54902001_PIP-CONN,H54902-001!!
S!RM1E1!!!!CONN3_G98259001!!CONN3_G98259001_PIP-CONN,G98259-001!!
S!J9A1!!!!CONN4_D42317002!!CONN4_D42317002_PIP-CONN,D42317-002!!
S!J1F3!!!!CONN8_H62179001!!CONN8_H62179001_PIP-CONN,H62179-001!!
S!J9B1!!!!CONN9_H51826001!!CONN9_H51826001_PIP2-CONN,H51826-001!!
S!R8E39!10!DEFAULT_RESISTOR_11500OHM_2_1!!RES!!RES_0402-24.9K,1%,1/16W,CHIP,G21796-254!!
S!DS9A7!!!!LED!!LED_A1LF-GREEN,IC,D14725-022!!
S!DS9A4!!!!LED!!LED_A1LF-GREEN,IC,D14725-022!!
S!U1L2!!!!TTL1G86!!TTL1G86_SOTLF-74AHCT1G86,IC,D39848-001!!
S!C3B6!!DEFAULT_CAPACITOR_6.8e+07pF_2_1!!CAPP!!CAPP_3018-68UF,16V,20%,TANT,724613-112!!
S!C3T3!!DEFAULT_CAPACITOR_6.8e+07pF_2_1!!CAPP!!CAPP_3018-68UF,16V,20%,TANT,724613-112!!
S!C4F5!!DEFAULT_CAPACITOR_6.8e+07pF_2_1!!CAPP!!CAPP_3018-68UF,16V,20%,TANT,724613-112!!
S!C4F4!!DEFAULT_CAPACITOR_6.8e+07pF_2_1!!CAPP!!CAPP_3018-68UF,16V,20%,TANT,724613-112!!
S!C4B14!!DEFAULT_CAPACITOR_6.8e+07pF_2_1!!CAPP!!CAPP_3018-68UF,16V,20%,TANT,724613-112!!
S!C9T3!!DEFAULT_CAPACITOR_6.8e+07pF_2_1!!CAPP!!CAPP_3018-68UF,16V,20%,TANT,724613-112!!
S!C1M5!!DEFAULT_CAPACITOR_6.8e+07pF_2_1!!CAPP!!CAPP_3018-68UF,16V,20%,TANT,724613-112!!
S!C6N5!!DEFAULT_CAPACITOR_6.8e+07pF_2_1!!CAPP!!CAPP_3018-68UF,16V,20%,TANT,724613-112!!
S!C1R23!!DEFAULT_CAPACITOR_6.8e+07pF_2_1!!CAPP!!CAPP_3018-68UF,16V,20%,TANT,724613-112!!
S!C7M6!!DEFAULT_CAPACITOR_6.8e+07pF_2_1!!CAPP!!CAPP_3018-68UF,16V,20%,TANT,724613-112!!
S!C9M3!!DEFAULT_CAPACITOR_6.8e+07pF_2_1!!CAPP!!CAPP_3018-68UF,16V,20%,TANT,724613-112!!
S!C3T13!!DEFAULT_CAPACITOR_6.8e+07pF_2_1!!CAPP!!CAPP_3018-68UF,16V,20%,TANT,724613-112!!
S!C3T6!!DEFAULT_CAPACITOR_6.8e+07pF_2_1!!CAPP!!CAPP_3018-68UF,16V,20%,TANT,724613-112!!
S!C3T15!!DEFAULT_CAPACITOR_6.8e+07pF_2_1!!CAPP!!CAPP_3018-68UF,16V,20%,TANT,724613-112!!
S!C4M6!!DEFAULT_CAPACITOR_6.8e+07pF_2_1!!CAPP!!CAPP_3018-68UF,16V,20%,TANT,724613-112!!
S!C4M7!!DEFAULT_CAPACITOR_6.8e+07pF_2_1!!CAPP!!CAPP_3018-68UF,16V,20%,TANT,724613-112!!
S!C8E15!16!DEFAULT_CAPACITOR_100.000000pF_2_1!!CAP!!CAP_0402LF-0.022UF,16V,10%,X7R,A36096-073!!
S!R7P9!!DEFAULT_RESISTOR_42.200000OHM_2_1!!RES!!RES_0402-42.2,1.0%,1/16W,EMPTY,G21796-259!!
S!R7P12!!DEFAULT_RESISTOR_42.200000OHM_2_1!!RES!!RES_0402-42.2,1.0%,1/16W,EMPTY,G21796-259!!
S!R7P6!!DEFAULT_RESISTOR_42.200000OHM_2_1!!RES!!RES_0402-42.2,1.0%,1/16W,EMPTY,G21796-259!!
S!R7P7!!DEFAULT_RESISTOR_42.200000OHM_2_1!!RES!!RES_0402-42.2,1.0%,1/16W,EMPTY,G21796-259!!
S!R7P3!!DEFAULT_RESISTOR_42.200000OHM_2_1!!RES!!RES_0402-42.2,1.0%,1/16W,EMPTY,G21796-259!!
S!R7P4!!DEFAULT_RESISTOR_42.200000OHM_2_1!!RES!!RES_0402-42.2,1.0%,1/16W,EMPTY,G21796-259!!
S!R7P1!!DEFAULT_RESISTOR_42.200000OHM_2_1!!RES!!RES_0402-42.2,1.0%,1/16W,EMPTY,G21796-259!!
S!R7P2!!DEFAULT_RESISTOR_42.200000OHM_2_1!!RES!!RES_0402-42.2,1.0%,1/16W,EMPTY,G21796-259!!
S!R6P8!!DEFAULT_RESISTOR_42.200000OHM_2_1!!RES!!RES_0402-42.2,1.0%,1/16W,EMPTY,G21796-259!!
S!R6P5!!DEFAULT_RESISTOR_42.200000OHM_2_1!!RES!!RES_0402-42.2,1.0%,1/16W,EMPTY,G21796-259!!
S!R6P6!!DEFAULT_RESISTOR_42.200000OHM_2_1!!RES!!RES_0402-42.2,1.0%,1/16W,EMPTY,G21796-259!!
S!R6P3!!DEFAULT_RESISTOR_42.200000OHM_2_1!!RES!!RES_0402-42.2,1.0%,1/16W,EMPTY,G21796-259!!
S!R6P4!!DEFAULT_RESISTOR_42.200000OHM_2_1!!RES!!RES_0402-42.2,1.0%,1/16W,EMPTY,G21796-259!!
S!R6P1!!DEFAULT_RESISTOR_42.200000OHM_2_1!!RES!!RES_0402-42.2,1.0%,1/16W,EMPTY,G21796-259!!
S!R6P2!!DEFAULT_RESISTOR_42.200000OHM_2_1!!RES!!RES_0402-42.2,1.0%,1/16W,EMPTY,G21796-259!!
S!R6P11!!DEFAULT_RESISTOR_42.200000OHM_2_1!!RES!!RES_0402-42.2,1.0%,1/16W,EMPTY,G21796-259!!
S!R6P9!!DEFAULT_RESISTOR_42.200000OHM_2_1!!RES!!RES_0402-42.2,1.0%,1/16W,EMPTY,G21796-259!!
S!R6P13!!DEFAULT_RESISTOR_42.200000OHM_2_1!!RES!!RES_0402-42.2,1.0%,1/16W,EMPTY,G21796-259!!
S!R6P12!!DEFAULT_RESISTOR_42.200000OHM_2_1!!RES!!RES_0402-42.2,1.0%,1/16W,EMPTY,G21796-259!!
S!R4D24!!DEFAULT_RESISTOR_42.200000OHM_2_1!!RES!!RES_0402-42.2,1.0%,1/16W,EMPTY,G21796-259!!
S!R4D18!!DEFAULT_RESISTOR_42.200000OHM_2_1!!RES!!RES_0402-42.2,1.0%,1/16W,EMPTY,G21796-259!!
S!R6P17!!DEFAULT_RESISTOR_42.200000OHM_2_1!!RES!!RES_0402-42.2,1.0%,1/16W,EMPTY,G21796-259!!
S!R6P15!!DEFAULT_RESISTOR_42.200000OHM_2_1!!RES!!RES_0402-42.2,1.0%,1/16W,EMPTY,G21796-259!!
S!R6P7!!DEFAULT_RESISTOR_42.200000OHM_2_1!!RES!!RES_0402-42.2,1.0%,1/16W,EMPTY,G21796-259!!
S!R9P24!19!DEFAULT_RESISTOR_15000OHM_2_1!!RES!!RES_0402-12.1K,1%,1/16W,CHIP,G21796-089!!
S!R1D41!23!RES_0402-0.0_5%_1/16W_CHIP_G21A_0.0!!RES!!RES_0805-0.0,5%,1/8W,CHIP,G22179-004!!
S!L8F1!!DEFAULT_INDUCTOR_470.000000nH_2_1!!INDUCTOR!!INDUCTOR_SM-1.00UH,IND,E98679-006!!
S!L8E1!!DEFAULT_INDUCTOR_1200nH_2_1!!INDUCTOR!!INDUCTOR_SM-2.2UH,IND,E98761-003!!
S!C7F10!26!DEFAULT_CAPACITOR_10000pF_2_1!!CAP!!CAP_0402-0.027UF,16V,10%,X7R,A36096-129!!
S!C7B11!26!DEFAULT_CAPACITOR_27000pF_2_1!!CAP!!CAP_0402-0.027UF,16V,10%,X7R,A36096-129!!
S!C4G8!26!DEFAULT_CAPACITOR_27000pF_2_1!!CAP!!CAP_0402-0.027UF,16V,10%,X7R,A36096-129!!
S!C4B6!26!DEFAULT_CAPACITOR_27000pF_2_1!!CAP!!CAP_0402-0.027UF,16V,10%,X7R,A36096-129!!
S!R3P51!!DEFAULT_RESISTOR_5760OHM_2_1!!RES!!RES_0402-6.34K,1%,1/16W,CHIP,G21796-146!!
S!R7F11!7!DEFAULT_RESISTOR_10000OHM_2_1!!RES!!RES_0402-6.34K,1%,1/16W,CHIP,G21796-146!!
S!R7B13!7!DEFAULT_RESISTOR_6340OHM_2_1!!RES!!RES_0402-6.34K,1%,1/16W,CHIP,G21796-146!!
S!R4G9!7!DEFAULT_RESISTOR_6340OHM_2_1!!RES!!RES_0402-6.34K,1%,1/16W,CHIP,G21796-146!!
S!R4B4!7!DEFAULT_RESISTOR_6340OHM_2_1!!RES!!RES_0402-6.34K,1%,1/16W,CHIP,G21796-146!!
S!R8F9!!DEFAULT_RESISTOR_63.400000OHM_2_1!!RES!!RES_0402-64.9K,1%,1/16W,CHIP,G21796-148!!
S!R7F15!!DEFAULT_RESISTOR_42200OHM_2_1!!RES!!RES_0402-7.87K,1.0%,1/16W,CHIP,G21796-242!!
S!R7F18!13!DEFAULT_RESISTOR_0.001OHM_2_1!!RES!!RES_0402-7.87K,1.0%,1/16W,CHIP,G21796-242!!
S!R7B16!13!DEFAULT_RESISTOR_7870OHM_2_1!!RES!!RES_0402-7.87K,1.0%,1/16W,CHIP,G21796-242!!
S!R7B14!!DEFAULT_RESISTOR_7870OHM_2_1!!RES!!RES_0402-7.87K,1.0%,1/16W,CHIP,G21796-242!!
S!R4G11!!DEFAULT_RESISTOR_7870OHM_2_1!!RES!!RES_0402-7.87K,1.0%,1/16W,CHIP,G21796-242!!
S!R4B6!!DEFAULT_RESISTOR_7870OHM_2_1!!RES!!RES_0402-7.87K,1.0%,1/16W,CHIP,G21796-242!!
S!R4G13!13!DEFAULT_RESISTOR_7870OHM_2_1!!RES!!RES_0402-7.87K,1.0%,1/16W,CHIP,G21796-242!!
S!R4B8!13!DEFAULT_RESISTOR_7870OHM_2_1!!RES!!RES_0402-7.87K,1.0%,1/16W,CHIP,G21796-242!!
S!R9P7!!DEFAULT_RESISTOR_16000OHM_2_1!!RES!!RES_0402-249K,1.0%,1/16W,CHIP,G21796-189!!
S!R9P13!!DEFAULT_RESISTOR_18200OHM_2_1!!RES!!RES_0402-274K,1.0%,1/16W,CHIP,G21796-331!!
S!J8G1!109!!!SCONN200_H68296001!!SCONN200_H68296001_SM-CONN,H68296-001!!
S!U8D8!!!!TPS3700!!TPS3700_SM-IC,H69492-001!!
S!U9P2!!!!TPS3700!!TPS3700_SM-IC,H69492-001!!
S!U1D2!!!!TPS3700!!TPS3700_SM-IC,H69492-001!!
S!U9P1!!!!TPS3700!!TPS3700_SM-IC,H69492-001!!
S!VR1D1!!!!ZENER!!ZENER_SM-13V,IC,H69095-001!!
S!DS9A1!!!!LED!!LED_1NC-BLUE,IC,C96565-012!!
S!DS9A3!!!!LED!!LED_1NCLF-YELLOW,IC,C96565-003!!
S!C8D3!!DEFAULT_CAPACITOR_470.000000pF_2_1!!CAP!!CAP_0402LF-470PF,50V,10%,EMPTY,A36096-049!!
S!C2R6!!DEFAULT_CAPACITOR_470.000000pF_2_1!!CAP!!CAP_0402LF-470PF,50V,10%,EMPTY,A36096-049!!
S!R8B21!!DEFAULT_RESISTOR_1000.000000OHM_2_1!!RES!!RES_0402-49.9,1%,1/16W,EMPTY,G21796-047!!
S!R3N14!!DEFAULT_RESISTOR_1000.000000OHM_2_1!!RES!!RES_0402-49.9,1%,1/16W,EMPTY,G21796-047!!
S!R3T11!92!RES_0402-49.9_1%_1/16W_EMPTY_GA_NA!!RES!!RES_0402-49.9,1%,1/16W,EMPTY,G21796-047!!
S!R9U4!!RES_0402-49.9_1%_1/16W_EMPTY_GA_NA!!RES!!RES_0402-49.9,1%,1/16W,EMPTY,G21796-047!!
S!R3P17!411!RES_0402-49.9_1%_1/16W_EMPTY_GA_NA!!RES!!RES_0402-49.9,1%,1/16W,EMPTY,G21796-047!!
S!XBT8G1!!!!VERT_BATT_3PIN!!VERT_BATT_3PIN_TH-3PVERT,C68619-005!!
S!CR3U1!!!!DIODE!!DIODE_SMLF-1N5819HW,IC,D55839-001!!
S!R1D20!!DEFAULT_RESISTOR_226000OHM_2_1!!RES!!RES_0402-150.0K,1%,1/16W,CHIP,G21796-109!!
S!R9P17!8!RES_0402-0.0_5%_1/16W_CHIP_G21A_0.0!!RES!!RES_0402-150.0K,1%,1/16W,CHIP,G21796-109!!
S!S8E1!!!!SWITCH_D90553001!!SWITCH_D90553001_SMLF-IC,D90553-001!!
S!C6F4!28!DEFAULT_CAPACITOR_4.7e+08pF_2_1!!CAPP!!CAPP_7343LF-330UF,6.3V,20%,POSCAP,724613-042!!
S!C6B7!28!DEFAULT_CAPACITOR_3.3e+08pF_2_1!!CAPP!!CAPP_7343LF-330UF,6.3V,20%,POSCAP,724613-042!!
S!C4F7!28!DEFAULT_CAPACITOR_3.3e+08pF_2_1!!CAPP!!CAPP_7343LF-330UF,6.3V,20%,POSCAP,724613-042!!
S!C3B3!28!DEFAULT_CAPACITOR_3.3e+08pF_2_1!!CAPP!!CAPP_7343LF-330UF,6.3V,20%,POSCAP,724613-042!!
S!C8F14!28!DEFAULT_CAPACITOR_4.7e+08pF_2_1!!CAPP!!CAPP_3018-470UF,6.3V,20%,POSCAP,724613-091!!
S!C8F8!28!DEFAULT_CAPACITOR_4.7e+08pF_2_1!!CAPP!!CAPP_3018-470UF,6.3V,20%,POSCAP,724613-091!!
S!C8E4!28!DEFAULT_CAPACITOR_4.7e+08pF_2_1!!CAPP!!CAPP_3018-470UF,6.3V,20%,POSCAP,724613-091!!
S!U9F2!!!!FSA3357!!FSA3357_SM-IC,C63273-001!!
S!U9F1!!!!FSA3357!!FSA3357_SM-IC,C63273-001!!
S!TC1A1!!!!RCC_DFX1940!!RCC_DFX1940_ID4-EMPTY,N_A!!
S!TC9A1!!!!RCC_DFX1940!!RCC_DFX1940_ID4-EMPTY,N_A!!
S!TC1G1!!!!RCC_DFX1940!!RCC_DFX1940_ID4-EMPTY,N_A!!
S!TC9F1!!!!RCC_DFX1940!!RCC_DFX1940_ID4-EMPTY,N_A!!
S!LB2F1!!!!SNLABEL_A!!SNLABEL_A_LABEL-EMPTY,N_A!!
S!LB5F1!!!!SNLABEL_A!!SNLABEL_A_LABEL-EMPTY,N_A!!
S!LB2B1!!!!SNLABEL_A!!SNLABEL_A_LABEL-EMPTY,N_A!!
S!LB5B1!!!!SNLABEL_A!!SNLABEL_A_LABEL-EMPTY,N_A!!
S!LB6T1!!!!SNLABEL_A!!SNLABEL_A_LABEL-EMPTY,N_A!!
S!S9A2!!!!SW_H67881001!!SW_H67881001_SM-IC,H67881-001!!
S!U1M3!!!!TPS2061!!TPS2061_SM-IC,H66405-001!!
S!C9G12!!CAP_0402LF-4700PF_50V_10%_EMPTA_NA!YES!CAP!!CAP_0402LF-4700PF,50V,10%,EMPTY,A36096-066!!
S!C9G13!!CAP_0402LF-4700PF_50V_10%_EMPTA_NA!YES!CAP!!CAP_0402LF-4700PF,50V,10%,EMPTY,A36096-066!!
S!C9G9!!CAP_0402LF-4700PF_50V_10%_EMPTA_NA!YES!CAP!!CAP_0402LF-4700PF,50V,10%,EMPTY,A36096-066!!
S!C9G16!!CAP_0402LF-4700PF_50V_10%_EMPTA_NA!YES!CAP!!CAP_0402LF-4700PF,50V,10%,EMPTY,A36096-066!!
S!C4T4!!DEFAULT_CAPACITOR_2.2e+07pF_2_1!!CAP!!CAP_0805-100UF,4V,20%,X5R,602433-112!!
S!C5U10!!DEFAULT_CAPACITOR_2.2e+07pF_2_1!!CAP!!CAP_0805-100UF,4V,20%,X5R,602433-112!!
S!C5U14!!DEFAULT_CAPACITOR_2.2e+07pF_2_1!!CAP!!CAP_0805-100UF,4V,20%,X5R,602433-112!!
S!C5U1!!DEFAULT_CAPACITOR_2.2e+07pF_2_1!!CAP!!CAP_0805-100UF,4V,20%,X5R,602433-112!!
S!C5U13!!DEFAULT_CAPACITOR_2.2e+07pF_2_1!!CAP!!CAP_0805-100UF,4V,20%,X5R,602433-112!!
S!C5U15!!DEFAULT_CAPACITOR_2.2e+07pF_2_1!!CAP!!CAP_0805-100UF,4V,20%,X5R,602433-112!!
S!C5G9!!DEFAULT_CAPACITOR_2.2e+07pF_2_1!!CAP!!CAP_0805-100UF,4V,20%,X5R,602433-112!!
S!C5G20!!DEFAULT_CAPACITOR_2.2e+07pF_2_1!!CAP!!CAP_0805-100UF,4V,20%,X5R,602433-112!!
S!C2G16!!DEFAULT_CAPACITOR_2.2e+07pF_2_1!!CAP!!CAP_0805-100UF,4V,20%,X5R,602433-112!!
S!C2G7!!DEFAULT_CAPACITOR_2.2e+07pF_2_1!!CAP!!CAP_0805-100UF,4V,20%,X5R,602433-112!!
S!C7U7!!DEFAULT_CAPACITOR_2.2e+07pF_2_1!!CAP!!CAP_0805-100UF,4V,20%,X5R,602433-112!!
S!C7T1!!DEFAULT_CAPACITOR_2.2e+07pF_2_1!!CAP!!CAP_0805-100UF,4V,20%,X5R,602433-112!!
S!C8U11!!DEFAULT_CAPACITOR_2.2e+07pF_2_1!!CAP!!CAP_0805-100UF,4V,20%,X5R,602433-112!!
S!C8U12!!DEFAULT_CAPACITOR_2.2e+07pF_2_1!!CAP!!CAP_0805-100UF,4V,20%,X5R,602433-112!!
S!C8U8!!DEFAULT_CAPACITOR_2.2e+07pF_2_1!!CAP!!CAP_0805-100UF,4V,20%,X5R,602433-112!!
S!C8U1!!DEFAULT_CAPACITOR_2.2e+07pF_2_1!!CAP!!CAP_0805-100UF,4V,20%,X5R,602433-112!!
S!C8L1!31!DEFAULT_CAPACITOR_2.2e+07pF_2_1!!CAP!!CAP_0805-100UF,4V,20%,X5R,602433-112!!
S!C7L1!43!DEFAULT_CAPACITOR_2.2e+07pF_2_1!!CAP!!CAP_0805-100UF,4V,20%,X5R,602433-112!!
S!C8M11!46!DEFAULT_CAPACITOR_2.2e+07pF_2_1!!CAP!!CAP_0805-100UF,4V,20%,X5R,602433-112!!
S!C8M7!18!DEFAULT_CAPACITOR_2.2e+07pF_2_1!!CAP!!CAP_0805-100UF,4V,20%,X5R,602433-112!!
S!C2A16!23!DEFAULT_CAPACITOR_2.2e+07pF_2_1!!CAP!!CAP_0805-100UF,4V,20%,X5R,602433-112!!
S!C8L11!29!DEFAULT_CAPACITOR_2.2e+07pF_2_1!!CAP!!CAP_0805-100UF,4V,20%,X5R,602433-112!!
S!C8L2!39!DEFAULT_CAPACITOR_2.2e+07pF_2_1!!CAP!!CAP_0805-100UF,4V,20%,X5R,602433-112!!
S!C2A8!52!DEFAULT_CAPACITOR_2.2e+07pF_2_1!!CAP!!CAP_0805-100UF,4V,20%,X5R,602433-112!!
S!C5A10!97!DEFAULT_CAPACITOR_2.2e+07pF_2_1!!CAP!!CAP_0805-100UF,4V,20%,X5R,602433-112!!
S!C5L1!!DEFAULT_CAPACITOR_2.2e+07pF_2_1!!CAP!!CAP_0805-100UF,4V,20%,X5R,602433-112!!
S!C5L3!!DEFAULT_CAPACITOR_2.2e+07pF_2_1!!CAP!!CAP_0805-100UF,4V,20%,X5R,602433-112!!
S!C5L14!!DEFAULT_CAPACITOR_2.2e+07pF_2_1!!CAP!!CAP_0805-100UF,4V,20%,X5R,602433-112!!
S!C5M8!!DEFAULT_CAPACITOR_2.2e+07pF_2_1!!CAP!!CAP_0805-100UF,4V,20%,X5R,602433-112!!
S!C5A20!!DEFAULT_CAPACITOR_2.2e+07pF_2_1!!CAP!!CAP_0805-100UF,4V,20%,X5R,602433-112!!
S!C5L2!!DEFAULT_CAPACITOR_2.2e+07pF_2_1!!CAP!!CAP_0805-100UF,4V,20%,X5R,602433-112!!
S!C5M12!!DEFAULT_CAPACITOR_2.2e+07pF_2_1!!CAP!!CAP_0805-100UF,4V,20%,X5R,602433-112!!
S!Y9F1!!!!CRYSTAL!!CRYSTAL_SM-24.000MHZ,IC,D95126-001!!
S!R8E31!9!DEFAULT_RESISTOR_23200OHM_2_1!!RES!!RES_0402-23.2K,1%,1/16W,CHIP,G21796-114!!
S!EU8E1!!!!CSD87384M!!CSD87384M_SM-IC,H66258-001!!
S!EU9F3!!!!PI7C9X1172!!PI7C9X1172_QFN-IC,H66899-001!!
S!EU8F1!!!!RT8240!!RT8240_QFN-IC,H66262-001!!
S!J8E1!!!!SCONN11_H67026001!!SCONN11_H67026001_SM-CONN,H67026-001!!
S!J8B1!!!!SCONN24_H46321001!!SCONN24_H46321001_SM-SCONN,H46321-001!!
S!U8D7!!!!LCMXO2!!LCMXO2_256BGA-IC,H63395-001!!
S!R2R6!!DEFAULT_RESISTOR_51.000000OHM_2_1!!RES!!RES_0402-51,5.0%,1/16W,CHIP,G21497-048!!
S!R1U12!!DEFAULT_RESISTOR_51.000000OHM_2_1!!RES!!RES_0402-51,5.0%,1/16W,CHIP,G21497-048!!
S!R1U13!!DEFAULT_RESISTOR_51.000000OHM_2_1!!RES!!RES_0402-51,5.0%,1/16W,CHIP,G21497-048!!
S!R1U14!!DEFAULT_RESISTOR_51.000000OHM_2_1!!RES!!RES_0402-51,5.0%,1/16W,CHIP,G21497-048!!
S!F1L1!!!!FUSE!!FUSE_SMT-IC,H45581-001!!
S!R9F32!!DEFAULT_RESISTOR_4750OHM_2_1!!RES!!RES_0402-13K,1.0%,1/16W,CHIP,G21796-221!!
S!S9A1!!!!SWITCH_D37771002!!SWITCH_D37771002_SM-IC,D37771-002!!
S!L7G1!7!DEFAULT_INDUCTOR_150.000000nH_2_1!!INDUCTOR!!INDUCTOR_SM-0.12UH,IND,D92183-034!!
S!L7G2!3!DEFAULT_INDUCTOR_150.000000nH_2_1!!INDUCTOR!!INDUCTOR_SM-0.12UH,IND,D92183-034!!
S!L7A1!6!DEFAULT_INDUCTOR_150.000000nH_2_1!!INDUCTOR!!INDUCTOR_SM-0.12UH,IND,D92183-034!!
S!L7A3!2!DEFAULT_INDUCTOR_150.000000nH_2_1!!INDUCTOR!!INDUCTOR_SM-0.12UH,IND,D92183-034!!
S!L1A2!59!DEFAULT_INDUCTOR_150.000000nH_2_1!!INDUCTOR!!INDUCTOR_SM-0.12UH,IND,D92183-034!!
S!L1A1!57!DEFAULT_INDUCTOR_150.000000nH_2_1!!INDUCTOR!!INDUCTOR_SM-0.12UH,IND,D92183-034!!
S!L1G1!!DEFAULT_INDUCTOR_150.000000nH_2_1!!INDUCTOR!!INDUCTOR_SM-0.12UH,IND,D92183-034!!
S!L1F2!!DEFAULT_INDUCTOR_150.000000nH_2_1!!INDUCTOR!!INDUCTOR_SM-0.12UH,IND,D92183-034!!
S!L4D2!!DEFAULT_INDUCTOR_150.000000nH_2_1!!INDUCTOR!!INDUCTOR_SM-0.12UH,IND,D92183-034!!
S!L4D1!!DEFAULT_INDUCTOR_150.000000nH_2_1!!INDUCTOR!!INDUCTOR_SM-0.12UH,IND,D92183-034!!
S!L4C3!96!DEFAULT_INDUCTOR_150.000000nH_2_1!!INDUCTOR!!INDUCTOR_SM-0.12UH,IND,D92183-034!!
S!L4D3!93!DEFAULT_INDUCTOR_150.000000nH_2_1!!INDUCTOR!!INDUCTOR_SM-0.12UH,IND,D92183-034!!
S!L4E1!91!DEFAULT_INDUCTOR_150.000000nH_2_1!!INDUCTOR!!INDUCTOR_SM-0.12UH,IND,D92183-034!!
S!L1D3!!DEFAULT_INDUCTOR_150.000000nH_2_1!!INDUCTOR!!INDUCTOR_SM-0.12UH,IND,D92183-034!!
S!L1E1!!DEFAULT_INDUCTOR_150.000000nH_2_1!!INDUCTOR!!INDUCTOR_SM-0.12UH,IND,D92183-034!!
S!L1D2!!DEFAULT_INDUCTOR_150.000000nH_2_1!!INDUCTOR!!INDUCTOR_SM-0.12UH,IND,D92183-034!!
S!L1D1!!DEFAULT_INDUCTOR_150.000000nH_2_1!!INDUCTOR!!INDUCTOR_SM-0.12UH,IND,D92183-034!!
S!L1C2!!DEFAULT_INDUCTOR_150.000000nH_2_1!!INDUCTOR!!INDUCTOR_SM-0.12UH,IND,D92183-034!!
S!R9F31!!DEFAULT_RESISTOR_4700OHM_2_1!!RES!!RES_0402-12K,1%,1/16W,CHIP,G21796-264!!
S!EU9F1!!!!RT9059!!RT9059_DFN-IC,H65765-001!!
S!EU8A2!73!!!RT9059!!RT9059_DFN-IC,H65765-001!!
S!EU9F2!!!!RT9059!!RT9059_DFN-IC,H65765-001!!
S!U7D3!!!!ADM1085!!ADM1085_SMT-IC,H46130-001!!
S!C3P45!!DEFAULT_CAPACITOR_47000pF_2_1!!CAP!!CAP_0402-0.047UF,25V,10%,X7R,A36096-090!!
S!C8D4!!!!CAP!!CAP_0402-0.1UF,16V,10%,X7R,A36096-030!!
S!C9M8!!DEFAULT_CAPACITOR_100000pF_2_1!!CAP!!CAP_0402-0.1UF,16V,10%,X7R,A36096-030!!
S!C9M7!!DEFAULT_CAPACITOR_100000pF_2_1!!CAP!!CAP_0402-0.1UF,16V,10%,X7R,A36096-030!!
S!C8E3!!DEFAULT_CAPACITOR_100000pF_2_1!!CAP!!CAP_0402-0.1UF,16V,10%,X7R,A36096-030!!
S!C1L16!!DEFAULT_CAPACITOR_100000pF_2_1!!CAP!!CAP_0402-0.1UF,16V,10%,X7R,A36096-030!!
S!C3P46!!DEFAULT_CAPACITOR_100000pF_2_1!!CAP!!CAP_0402-0.1UF,16V,10%,X7R,A36096-030!!
S!R3P54!!!!RES!!RES_0402-3.32K,1%,1/16W,EMPTY,G21796-027!!
S!R1C35!!!!RES!!RES_0402-3.32K,1%,1/16W,EMPTY,G21796-027!!
S!R1R6!!DEFAULT_RESISTOR_3320OHM_2_1!!RES!!RES_0402-3.32K,1%,1/16W,EMPTY,G21796-027!!
S!R1U38!!DEFAULT_RESISTOR_8250OHM_2_1!!RES!!RES_0402-8.2K,1%,1/16W,CHIP,G21796-345!!
S!R1U27!!DEFAULT_RESISTOR_8250OHM_2_1!!RES!!RES_0402-8.2K,1%,1/16W,CHIP,G21796-345!!
S!R1T25!!DEFAULT_RESISTOR_8200OHM_2_1!!RES!!RES_0402-8.2K,1%,1/16W,CHIP,G21796-345!!
S!C8F6!!CAP_0402LF-0.01UF_25V_10%_EMPTA_NA!YES!CAP!!CAP_0402LF-0.01UF,25V,10%,EMPTY,A36096-045!!
S!C8F11!!CAP_0402LF-0.01UF_25V_10%_EMPTA_NA!YES!CAP!!CAP_0402LF-0.01UF,25V,10%,EMPTY,A36096-045!!
S!C8F13!!CAP_0402LF-0.01UF_25V_10%_EMPTA_NA!YES!CAP!!CAP_0402LF-0.01UF,25V,10%,EMPTY,A36096-045!!
S!C8F15!!CAP_0402LF-0.01UF_25V_10%_EMPTA_NA!YES!CAP!!CAP_0402LF-0.01UF,25V,10%,EMPTY,A36096-045!!
S!L1L1!!!!CHOKE_4PIN!!CHOKE_4PIN_SM_B-67 OHM,EMPTY,752402-028!!
S!L1M1!!!!CHOKE_4PIN!!CHOKE_4PIN_SM_B-67 OHM,EMPTY,752402-028!!
S!R7A15!29!!!RES!!RES_0402-2.2,5%,1/16W,EMPTY,G21497-016!!
S!R4F6!29!!!RES!!RES_0402-2.2,5%,1/16W,EMPTY,G21497-016!!
S!R4A7!29!!!RES!!RES_0402-2.2,5%,1/16W,EMPTY,G21497-016!!
S!R7F7!29!!!RES!!RES_0402-2.2,5%,1/16W,EMPTY,G21497-016!!
S!R8F3!29!!!RES!!RES_0402-2.2,5%,1/16W,EMPTY,G21497-016!!
S!R1L43!!DEFAULT_RESISTOR_330.000000OHM_2_1!!RES!!RES_0402-330,5%,1/16W,CHIP,G21497-028!!
S!R1L44!!DEFAULT_RESISTOR_330.000000OHM_2_1!!RES!!RES_0402-330,5%,1/16W,CHIP,G21497-028!!
S!R2T4!34!DEFAULT_RESISTOR_121.000000OHM_2_1!!RES!!RES_0402-1.0K,0.1%,1/16W,CHIP,G85996-004!!
S!R8E18!34!DEFAULT_RESISTOR_121.000000OHM_2_1!!RES!!RES_0402-1.0K,0.1%,1/16W,CHIP,G85996-004!!
S!R7F17!29!DEFAULT_RESISTOR_1000.000000OHM_2_1!!RES!!RES_0402-1.0K,0.1%,1/16W,CHIP,G85996-004!!
S!R7B18!9!DEFAULT_RESISTOR_1000.000000OHM_2_1!!RES!!RES_0402-1.0K,0.1%,1/16W,CHIP,G85996-004!!
S!R4G10!9!DEFAULT_RESISTOR_1000.000000OHM_2_1!!RES!!RES_0402-1.0K,0.1%,1/16W,CHIP,G85996-004!!
S!R4B9!9!DEFAULT_RESISTOR_1000.000000OHM_2_1!!RES!!RES_0402-1.0K,0.1%,1/16W,CHIP,G85996-004!!
S!R2N4!!DEFAULT_RESISTOR_1000.000000OHM_2_1!!RES!!RES_0402-1.0K,0.1%,1/16W,CHIP,G85996-004!!
S!R2M6!!DEFAULT_RESISTOR_1000.000000OHM_2_1!!RES!!RES_0402-1.0K,0.1%,1/16W,CHIP,G85996-004!!
S!R7E16!7!DEFAULT_RESISTOR_9310OHM_2_1!!RES!!RES_0402-1.37K,1%,1/16W,CHIP,G21796-095!!
S!R1C34!!!!RES!!RES_0402-10.0K,1%,1/16W,CHIP,G21796-016!!
S!R9F61!!!!RES!!RES_0402-10.0K,1%,1/16W,CHIP,G21796-016!!
S!R1M25!!!!RES!!RES_0402-10.0K,1%,1/16W,CHIP,G21796-016!!
S!R2P18!!!!RES!!RES_0402-10.0K,1%,1/16W,CHIP,G21796-016!!
S!R8D41!!!!RES!!RES_0402-10.0K,1%,1/16W,CHIP,G21796-016!!
S!R2P21!!!!RES!!RES_0402-10.0K,1%,1/16W,CHIP,G21796-016!!
S!R8B32!!!!RES!!RES_0402-10.0K,1%,1/16W,CHIP,G21796-016!!
S!R8F36!!!!RES!!RES_0402-10.0K,1%,1/16W,CHIP,G21796-016!!
S!R1R12!!DEFAULT_RESISTOR_10000OHM_2_1!!RES!!RES_0402-10.0K,1%,1/16W,CHIP,G21796-016!!
S!R7B7!!DEFAULT_RESISTOR_10000OHM_2_1!!RES!!RES_0402-10.0K,1%,1/16W,CHIP,G21796-016!!
S!R7B8!!DEFAULT_RESISTOR_10000OHM_2_1!!RES!!RES_0402-10.0K,1%,1/16W,CHIP,G21796-016!!
S!R7C20!!DEFAULT_RESISTOR_10000OHM_2_1!!RES!!RES_0402-10.0K,1%,1/16W,CHIP,G21796-016!!
S!R7C23!!!!RES!!RES_0402-10.0K,1%,1/16W,CHIP,G21796-016!!
S!R7G22!!RES_0402-4.75K_1%_1/16W_CHIP_GA_4.75K!!RES!!RES_0402-10.0K,1%,1/16W,CHIP,G21796-016!!
S!R7G23!!RES_0402-4.75K_1%_1/16W_CHIP_GA_4.75K!!RES!!RES_0402-10.0K,1%,1/16W,CHIP,G21796-016!!
S!R8G20!!RES_0402-4.75K_1%_1/16W_CHIP_GA_4.75K!!RES!!RES_0402-10.0K,1%,1/16W,CHIP,G21796-016!!
S!R2N9!!DEFAULT_RESISTOR_10000OHM_2_1!!RES!!RES_0402-10.0K,1%,1/16W,CHIP,G21796-016!!
S!R8D30!!DEFAULT_RESISTOR_10000OHM_2_1!!RES!!RES_0402-10.0K,1%,1/16W,CHIP,G21796-016!!
S!R6F3!!DEFAULT_RESISTOR_10000OHM_2_1!!RES!!RES_0402-10.0K,1%,1/16W,CHIP,G21796-016!!
S!R1U7!!DEFAULT_RESISTOR_10000OHM_2_1!!RES!!RES_0402-10.0K,1%,1/16W,CHIP,G21796-016!!
S!R9P5!!DEFAULT_RESISTOR_10000OHM_2_1!!RES!!RES_0402-10.0K,1%,1/16W,CHIP,G21796-016!!
S!R2P19!!DEFAULT_RESISTOR_10000OHM_2_1!!RES!!RES_0402-10.0K,1%,1/16W,CHIP,G21796-016!!
S!R1M11!!DEFAULT_RESISTOR_10000OHM_2_1!!RES!!RES_0402-10.0K,1%,1/16W,CHIP,G21796-016!!
S!R1M12!!DEFAULT_RESISTOR_10000OHM_2_1!!RES!!RES_0402-10.0K,1%,1/16W,CHIP,G21796-016!!
S!R4P5!!DEFAULT_RESISTOR_10000OHM_2_1!!RES!!RES_0402-10.0K,1%,1/16W,CHIP,G21796-016!!
S!R7P13!!DEFAULT_RESISTOR_10000OHM_2_1!!RES!!RES_0402-10.0K,1%,1/16W,CHIP,G21796-016!!
S!R1U6!!DEFAULT_RESISTOR_10000OHM_2_1!!RES!!RES_0402-10.0K,1%,1/16W,CHIP,G21796-016!!
S!R2N13!!DEFAULT_RESISTOR_10000OHM_2_1!!RES!!RES_0402-10.0K,1%,1/16W,CHIP,G21796-016!!
S!R3T12!!DEFAULT_RESISTOR_10000OHM_2_1!!RES!!RES_0402-10.0K,1%,1/16W,CHIP,G21796-016!!
S!R3T4!!DEFAULT_RESISTOR_10000OHM_2_1!!RES!!RES_0402-10.0K,1%,1/16W,CHIP,G21796-016!!
S!R1D23!!DEFAULT_RESISTOR_10000OHM_2_1!!RES!!RES_0402-10.0K,1%,1/16W,CHIP,G21796-016!!
S!R1D10!!DEFAULT_RESISTOR_10000OHM_2_1!!RES!!RES_0402-10.0K,1%,1/16W,CHIP,G21796-016!!
S!R9P10!!DEFAULT_RESISTOR_10000OHM_2_1!!RES!!RES_0402-10.0K,1%,1/16W,CHIP,G21796-016!!
S!R9P11!!DEFAULT_RESISTOR_10000OHM_2_1!!RES!!RES_0402-10.0K,1%,1/16W,CHIP,G21796-016!!
S!R1D12!!DEFAULT_RESISTOR_10000OHM_2_1!!RES!!RES_0402-10.0K,1%,1/16W,CHIP,G21796-016!!
S!R1D19!!DEFAULT_RESISTOR_10000OHM_2_1!!RES!!RES_0402-10.0K,1%,1/16W,CHIP,G21796-016!!
S!R9P9!!DEFAULT_RESISTOR_10000OHM_2_1!!RES!!RES_0402-10.0K,1%,1/16W,CHIP,G21796-016!!
S!R1D22!!DEFAULT_RESISTOR_10000OHM_2_1!!RES!!RES_0402-10.0K,1%,1/16W,CHIP,G21796-016!!
S!R3T14!!DEFAULT_RESISTOR_10000OHM_2_1!!RES!!RES_0402-10.0K,1%,1/16W,CHIP,G21796-016!!
S!R4G5!!DEFAULT_RESISTOR_10000OHM_2_1!!RES!!RES_0402-10.0K,1%,1/16W,CHIP,G21796-016!!
S!R1M24!!DEFAULT_RESISTOR_10000OHM_2_1!!RES!!RES_0402-10.0K,1%,1/16W,CHIP,G21796-016!!
S!R7F14!!DEFAULT_RESISTOR_10000OHM_2_1!!RES!!RES_0402-10.0K,1%,1/16W,CHIP,G21796-016!!
S!R8E34!7!DEFAULT_RESISTOR_10000OHM_2_1!!RES!!RES_0402-10.0K,1%,1/16W,CHIP,G21796-016!!
S!R2R3!!DEFAULT_RESISTOR_10000OHM_2_1!!RES!!RES_0402-10.0K,1%,1/16W,CHIP,G21796-016!!
S!R7E5!!DEFAULT_RESISTOR_10000OHM_2_1!!RES!!RES_0402-10.0K,1%,1/16W,CHIP,G21796-016!!
S!R2N6!!DEFAULT_RESISTOR_10000OHM_2_1!!RES!!RES_0402-10.0K,1%,1/16W,CHIP,G21796-016!!
S!R7E6!!DEFAULT_RESISTOR_10000OHM_2_1!!RES!!RES_0402-10.0K,1%,1/16W,CHIP,G21796-016!!
S!R2R1!!DEFAULT_RESISTOR_10000OHM_2_1!!RES!!RES_0402-10.0K,1%,1/16W,CHIP,G21796-016!!
S!R9P6!!DEFAULT_RESISTOR_10000OHM_2_1!!RES!!RES_0402-10.0K,1%,1/16W,CHIP,G21796-016!!
S!R7C5!!DEFAULT_RESISTOR_10000OHM_2_1!!RES!!RES_0402-10.0K,1%,1/16W,CHIP,G21796-016!!
S!R7C8!!DEFAULT_RESISTOR_10000OHM_2_1!!RES!!RES_0402-10.0K,1%,1/16W,CHIP,G21796-016!!
S!R7B6!!DEFAULT_RESISTOR_10000OHM_2_1!!RES!!RES_0402-10.0K,1%,1/16W,CHIP,G21796-016!!
S!R7D12!!DEFAULT_RESISTOR_10000OHM_2_1!!RES!!RES_0402-10.0K,1%,1/16W,CHIP,G21796-016!!
S!R7C13!!DEFAULT_RESISTOR_10000OHM_2_1!!RES!!RES_0402-10.0K,1%,1/16W,CHIP,G21796-016!!
S!R2N28!!DEFAULT_RESISTOR_10000OHM_2_1!!RES!!RES_0402-10.0K,1%,1/16W,CHIP,G21796-016!!
S!R8E3!!DEFAULT_RESISTOR_10000OHM_2_1!!RES!!RES_0402-10.0K,1%,1/16W,CHIP,G21796-016!!
S!R2N23!!DEFAULT_RESISTOR_10000OHM_2_1!!RES!!RES_0402-10.0K,1%,1/16W,CHIP,G21796-016!!
S!R7G26!!DEFAULT_RESISTOR_10000OHM_2_1!!RES!!RES_0402-10.0K,1%,1/16W,CHIP,G21796-016!!
S!R8E36!!DEFAULT_RESISTOR_10000OHM_2_1!!RES!!RES_0402-10.0K,1%,1/16W,CHIP,G21796-016!!
S!R9F12!!DEFAULT_RESISTOR_10000OHM_2_1!!RES!!RES_0402-10.0K,1%,1/16W,CHIP,G21796-016!!
S!R2N16!!DEFAULT_RESISTOR_10000OHM_2_1!!RES!!RES_0402-10.0K,1%,1/16W,CHIP,G21796-016!!
S!R7C21!!DEFAULT_RESISTOR_10000OHM_2_1!!RES!!RES_0402-10.0K,1%,1/16W,CHIP,G21796-016!!
S!R8E16!!DEFAULT_RESISTOR_10000OHM_2_1!!RES!!RES_0402-10.0K,1%,1/16W,CHIP,G21796-016!!
S!R5N3!!DEFAULT_RESISTOR_10000OHM_2_1!!RES!!RES_0402-10.0K,1%,1/16W,CHIP,G21796-016!!
S!R5N5!!DEFAULT_RESISTOR_10000OHM_2_1!!RES!!RES_0402-10.0K,1%,1/16W,CHIP,G21796-016!!
S!R5N1!!DEFAULT_RESISTOR_10000OHM_2_1!!RES!!RES_0402-10.0K,1%,1/16W,CHIP,G21796-016!!
S!R8N3!!DEFAULT_RESISTOR_10000OHM_2_1!!RES!!RES_0402-10.0K,1%,1/16W,CHIP,G21796-016!!
S!R8N5!!DEFAULT_RESISTOR_10000OHM_2_1!!RES!!RES_0402-10.0K,1%,1/16W,CHIP,G21796-016!!
S!R8N2!!DEFAULT_RESISTOR_10000OHM_2_1!!RES!!RES_0402-10.0K,1%,1/16W,CHIP,G21796-016!!
S!R9E1!!DEFAULT_RESISTOR_10000OHM_2_1!!RES!!RES_0402-10.0K,1%,1/16W,CHIP,G21796-016!!
S!R9E3!!DEFAULT_RESISTOR_10000OHM_2_1!!RES!!RES_0402-10.0K,1%,1/16W,CHIP,G21796-016!!
S!R9E2!!DEFAULT_RESISTOR_10000OHM_2_1!!RES!!RES_0402-10.0K,1%,1/16W,CHIP,G21796-016!!
S!R9E22!!DEFAULT_RESISTOR_10000OHM_2_1!!RES!!RES_0402-10.0K,1%,1/16W,CHIP,G21796-016!!
S!R9F13!!DEFAULT_RESISTOR_10000OHM_2_1!!RES!!RES_0402-10.0K,1%,1/16W,CHIP,G21796-016!!
S!R9F8!!DEFAULT_RESISTOR_10000OHM_2_1!!RES!!RES_0402-10.0K,1%,1/16W,CHIP,G21796-016!!
S!R8D13!!DEFAULT_RESISTOR_10000OHM_2_1!!RES!!RES_0402-10.0K,1%,1/16W,CHIP,G21796-016!!
S!R4G18!!DEFAULT_RESISTOR_10000OHM_2_1!!RES!!RES_0402-10.0K,1%,1/16W,CHIP,G21796-016!!
S!R7D8!!DEFAULT_RESISTOR_10000OHM_2_1!!RES!!RES_0402-10.0K,1%,1/16W,CHIP,G21796-016!!
S!R7D4!!DEFAULT_RESISTOR_10000OHM_2_1!!RES!!RES_0402-10.0K,1%,1/16W,CHIP,G21796-016!!
S!R7D10!!DEFAULT_RESISTOR_10000OHM_2_1!!RES!!RES_0402-10.0K,1%,1/16W,CHIP,G21796-016!!
S!R8F26!!DEFAULT_RESISTOR_10000OHM_2_1!!RES!!RES_0402-10.0K,1%,1/16W,CHIP,G21796-016!!
S!R2T22!!DEFAULT_RESISTOR_10000OHM_2_1!!RES!!RES_0402-10.0K,1%,1/16W,CHIP,G21796-016!!
S!R7F32!!DEFAULT_RESISTOR_10000OHM_2_1!YES!RES!!RES_0402-10.0K,1%,1/16W,CHIP,G21796-016!!
S!R7F28!!DEFAULT_RESISTOR_10000OHM_2_1!YES!RES!!RES_0402-10.0K,1%,1/16W,CHIP,G21796-016!!
S!R2T8!!DEFAULT_RESISTOR_10000OHM_2_1!!RES!!RES_0402-10.0K,1%,1/16W,CHIP,G21796-016!!
S!R6L9!!DEFAULT_RESISTOR_10000OHM_2_1!!RES!!RES_0402-10.0K,1%,1/16W,CHIP,G21796-016!!
S!R4G17!!DEFAULT_RESISTOR_10000OHM_2_1!!RES!!RES_0402-10.0K,1%,1/16W,CHIP,G21796-016!!
S!R4A5!!DEFAULT_RESISTOR_10000OHM_2_1!!RES!!RES_0402-10.0K,1%,1/16W,CHIP,G21796-016!!
S!R2P15!!DEFAULT_RESISTOR_10000OHM_2_1!!RES!!RES_0402-10.0K,1%,1/16W,CHIP,G21796-016!!
S!R2P16!!DEFAULT_RESISTOR_10000OHM_2_1!!RES!!RES_0402-10.0K,1%,1/16W,CHIP,G21796-016!!
S!R9E4!!DEFAULT_RESISTOR_10000OHM_2_1!!RES!!RES_0402-10.0K,1%,1/16W,CHIP,G21796-016!!
S!R8E30!!DEFAULT_RESISTOR_10000OHM_2_1!!RES!!RES_0402-10.0K,1%,1/16W,CHIP,G21796-016!!
S!R1R13!!DEFAULT_RESISTOR_10000OHM_2_1!!RES!!RES_0402-10.0K,1%,1/16W,CHIP,G21796-016!!
S!R1R10!!DEFAULT_RESISTOR_10000OHM_2_1!!RES!!RES_0402-10.0K,1%,1/16W,CHIP,G21796-016!!
S!R8F32!!DEFAULT_RESISTOR_10000OHM_2_1!!RES!!RES_0402-10.0K,1%,1/16W,CHIP,G21796-016!!
S!R1R4!!DEFAULT_RESISTOR_10000OHM_2_1!!RES!!RES_0402-10.0K,1%,1/16W,CHIP,G21796-016!!
S!R9E13!!DEFAULT_RESISTOR_10000OHM_2_1!!RES!!RES_0402-10.0K,1%,1/16W,CHIP,G21796-016!!
S!R1T1!!DEFAULT_RESISTOR_10000OHM_2_1!!RES!!RES_0402-10.0K,1%,1/16W,CHIP,G21796-016!!
S!R3N10!!DEFAULT_RESISTOR_10000OHM_2_1!!RES!!RES_0402-10.0K,1%,1/16W,CHIP,G21796-016!!
S!R7F1!9!DEFAULT_RESISTOR_10000OHM_2_1!!RES!!RES_0402-10.0K,1%,1/16W,CHIP,G21796-016!!
S!R8D39!!!!RES!!RES_0402-49.9K,1%,1/16W,CHIP,G21796-048!!
S!R9G7!!DEFAULT_RESISTOR_49.900000OHM_2_1!!RES!!RES_0402-49.9K,1%,1/16W,CHIP,G21796-048!!
S!R2L19!70!DEFAULT_RESISTOR_49900OHM_2_1!!RES!!RES_0402-49.9K,1%,1/16W,CHIP,G21796-048!!
S!R7E14!8!DEFAULT_RESISTOR_49.900000OHM_2_1!!RES!!RES_0402-75K,1%,1/16W,CHIP,G21796-224!!
S!EU7E2!!!!TPS54821!!TPS54821_LCC-IC,H63269-001!!
S!EU9G1!!!!ADC128D818!!ADC128D818_SM-IC,H63642-001!!
S!C7C4!!DEFAULT_CAPACITOR_27.000000pF_2_1!!CAP!!CAP_0402LF-15.0PF,50V,5%,COG,A36095-047!!
S!C7C5!!DEFAULT_CAPACITOR_27.000000pF_2_1!!CAP!!CAP_0402LF-15.0PF,50V,5%,COG,A36095-047!!
S!C8C1!!DEFAULT_CAPACITOR_27.000000pF_2_1!!CAP!!CAP_0402LF-33.0PF,50V,5%,COG,A36095-031!!
S!C8C2!!DEFAULT_CAPACITOR_27.000000pF_2_1!!CAP!!CAP_0402LF-33.0PF,50V,5%,COG,A36095-031!!
S!Y8C1!!!!CRYSTAL!!CRYSTAL_2013-25.000MHZ,IC,H19611-001!!
S!R8B11!!DEFAULT_RESISTOR_1800OHM_2_1!!RES!!RES_0402-1.8K,1%,1/16W,CHIP,G21796-336!!
S!R8B7!!DEFAULT_RESISTOR_1800OHM_2_1!!RES!!RES_0402-1.8K,1%,1/16W,CHIP,G21796-336!!
S!R8B6!!DEFAULT_RESISTOR_1800OHM_2_1!!RES!!RES_0402-1.8K,1%,1/16W,CHIP,G21796-336!!
S!R8B13!!DEFAULT_RESISTOR_1800OHM_2_1!!RES!!RES_0402-1.8K,1%,1/16W,CHIP,G21796-336!!
S!R5N2!!DEFAULT_RESISTOR_10000OHM_2_1!!RES!!RES_0402-1.8K,1%,1/16W,CHIP,G21796-336!!
S!R8N1!!DEFAULT_RESISTOR_8200OHM_2_1!!RES!!RES_0402-1.8K,1%,1/16W,CHIP,G21796-336!!
S!R5N4!!DEFAULT_RESISTOR_8200OHM_2_1!!RES!!RES_0402-1.8K,1%,1/16W,CHIP,G21796-336!!
S!R8N4!!DEFAULT_RESISTOR_8200OHM_2_1!!RES!!RES_0402-1.8K,1%,1/16W,CHIP,G21796-336!!
S!R3N1!!DEFAULT_RESISTOR_7500OHM_2_1!!RES!!RES_0402-169,1.0%,1/16W,CHIP,G21796-276!!
S!R7C1!!DEFAULT_RESISTOR_0.001OHM_2_1!!RES!!RES_0603-200K,0.1%,1/10W,CHIP,G22369-010!!
S!R1E11!!DEFAULT_RESISTOR_10000OHM_2_1!!RES!!RES_0402-10.0K,1%,1/16W,EMPTY,G21796-016!!
S!R8F1!!DEFAULT_RESISTOR_10000OHM_2_1!!RES!!RES_0402-10.0K,1%,1/16W,EMPTY,G21796-016!!
S!R2N12!!DEFAULT_RESISTOR_10000OHM_2_1!!RES!!RES_0402-10.0K,1%,1/16W,EMPTY,G21796-016!!
S!R3R11!!DEFAULT_RESISTOR_10000OHM_2_1!!RES!!RES_0402-10.0K,1%,1/16W,EMPTY,G21796-016!!
S!R7F30!!DEFAULT_RESISTOR_10000OHM_2_1!!RES!!RES_0402-10.0K,1%,1/16W,EMPTY,G21796-016!!
S!R3T9!!DEFAULT_RESISTOR_10000OHM_2_1!!RES!!RES_0402-10.0K,1%,1/16W,EMPTY,G21796-016!!
S!R3P50!!DEFAULT_RESISTOR_10000OHM_2_1!!RES!!RES_0402-10.0K,1%,1/16W,EMPTY,G21796-016!!
S!R8D16!!DEFAULT_RESISTOR_10000OHM_2_1!!RES!!RES_0402-10.0K,1%,1/16W,EMPTY,G21796-016!!
S!R4D35!!DEFAULT_RESISTOR_10000OHM_2_1!!RES!!RES_0402-10.0K,1%,1/16W,EMPTY,G21796-016!!
S!R4D38!!DEFAULT_RESISTOR_10000OHM_2_1!!RES!!RES_0402-10.0K,1%,1/16W,EMPTY,G21796-016!!
S!R9P19!!DEFAULT_RESISTOR_10000OHM_2_1!!RES!!RES_0402-10.0K,1%,1/16W,EMPTY,G21796-016!!
S!R2T12!!DEFAULT_RESISTOR_10000OHM_2_1!!RES!!RES_0402-10.0K,1%,1/16W,EMPTY,G21796-016!!
S!R5D5!!DEFAULT_RESISTOR_100.000000OHM_2_1!!RES!!RES_0402-249,0.1%,1/16W,CHIP,G85996-031!!
S!R3D27!!DEFAULT_RESISTOR_100.000000OHM_2_1!!RES!!RES_0402-249,0.1%,1/16W,CHIP,G85996-031!!
S!R9F6!!DEFAULT_RESISTOR_4700OHM_2_1!!RES!!RES_0402-5.76K,1%,1/16W,CHIP,G21796-143!!
S!R4D23!!DEFAULT_RESISTOR_27.400000OHM_2_1!!RES!!RES_0402-27.4,1%,1/16W,CHIP,G21796-182!!
S!R4D28!!DEFAULT_RESISTOR_27.400000OHM_2_1!!RES!!RES_0402-27.4,1%,1/16W,CHIP,G21796-182!!
S!R4D19!!DEFAULT_RESISTOR_27.400000OHM_2_1!!RES!!RES_0402-27.4,1%,1/16W,CHIP,G21796-182!!
S!R4D21!!DEFAULT_RESISTOR_27.400000OHM_2_1!!RES!!RES_0402-27.4,1%,1/16W,CHIP,G21796-182!!
S!R4D13!!DEFAULT_RESISTOR_27.400000OHM_2_1!!RES!!RES_0402-27.4,1%,1/16W,CHIP,G21796-182!!
S!R4D16!!DEFAULT_RESISTOR_27.400000OHM_2_1!!RES!!RES_0402-27.4,1%,1/16W,CHIP,G21796-182!!
S!R4D9!!DEFAULT_RESISTOR_27.400000OHM_2_1!!RES!!RES_0402-27.4,1%,1/16W,CHIP,G21796-182!!
S!R4D11!!DEFAULT_RESISTOR_27.400000OHM_2_1!!RES!!RES_0402-27.4,1%,1/16W,CHIP,G21796-182!!
S!R4D1!!DEFAULT_RESISTOR_27.400000OHM_2_1!!RES!!RES_0402-27.4,1%,1/16W,CHIP,G21796-182!!
S!R4D4!!DEFAULT_RESISTOR_27.400000OHM_2_1!!RES!!RES_0402-27.4,1%,1/16W,CHIP,G21796-182!!
S!R4D3!!DEFAULT_RESISTOR_27.400000OHM_2_1!!RES!!RES_0402-27.4,1%,1/16W,CHIP,G21796-182!!
S!R4D6!!DEFAULT_RESISTOR_27.400000OHM_2_1!!RES!!RES_0402-27.4,1%,1/16W,CHIP,G21796-182!!
S!R4D5!!DEFAULT_RESISTOR_27.400000OHM_2_1!!RES!!RES_0402-27.4,1%,1/16W,CHIP,G21796-182!!
S!R4D8!!DEFAULT_RESISTOR_27.400000OHM_2_1!!RES!!RES_0402-27.4,1%,1/16W,CHIP,G21796-182!!
S!R4D7!!DEFAULT_RESISTOR_27.400000OHM_2_1!!RES!!RES_0402-27.4,1%,1/16W,CHIP,G21796-182!!
S!R4D12!!DEFAULT_RESISTOR_27.400000OHM_2_1!!RES!!RES_0402-27.4,1%,1/16W,CHIP,G21796-182!!
S!R4D10!!DEFAULT_RESISTOR_27.400000OHM_2_1!!RES!!RES_0402-27.4,1%,1/16W,CHIP,G21796-182!!
S!R4D17!!DEFAULT_RESISTOR_27.400000OHM_2_1!!RES!!RES_0402-27.4,1%,1/16W,CHIP,G21796-182!!
S!R4D14!!DEFAULT_RESISTOR_27.400000OHM_2_1!!RES!!RES_0402-27.4,1%,1/16W,CHIP,G21796-182!!
S!R4D22!!DEFAULT_RESISTOR_27.400000OHM_2_1!!RES!!RES_0402-27.4,1%,1/16W,CHIP,G21796-182!!
S!R4D20!!DEFAULT_RESISTOR_27.400000OHM_2_1!!RES!!RES_0402-27.4,1%,1/16W,CHIP,G21796-182!!
S!R4D29!!DEFAULT_RESISTOR_27.400000OHM_2_1!!RES!!RES_0402-27.4,1%,1/16W,CHIP,G21796-182!!
S!R4D25!!DEFAULT_RESISTOR_27.400000OHM_2_1!!RES!!RES_0402-27.4,1%,1/16W,CHIP,G21796-182!!
S!R4D2!!DEFAULT_RESISTOR_27.400000OHM_2_1!!RES!!RES_0402-27.4,1%,1/16W,CHIP,G21796-182!!
S!L4C1!!DEFAULT_INDUCTOR_100.000000nH_2_1!!INDUCTOR!!INDUCTOR_SM-100NH,IND,D92183-019!!
S!L1B2!!DEFAULT_INDUCTOR_100.000000nH_2_1!!INDUCTOR!!INDUCTOR_SM-100NH,IND,D92183-019!!
S!L7F2!112!DEFAULT_INDUCTOR_100.000000nH_2_1!!INDUCTOR!!INDUCTOR_SM-100NH,IND,D92183-020!!
S!L1F1!!DEFAULT_INDUCTOR_100.000000nH_2_1!!INDUCTOR!!INDUCTOR_SM-100NH,IND,D92183-020!!
S!L1B1!49!DEFAULT_INDUCTOR_100.000000nH_2_1!!INDUCTOR!!INDUCTOR_SM-100NH,IND,D92183-020!!
S!L7A5!37!DEFAULT_INDUCTOR_100.000000nH_2_1!!INDUCTOR!!INDUCTOR_SM-100NH,IND,D92183-020!!
S!L7C1!432!DEFAULT_INDUCTOR_100.000000nH_2_1!!INDUCTOR!!INDUCTOR_SM-100NH,IND,D92183-020!!
S!EU4D2!!!!NB3W1200L!!NB3W1200L_LCC-IC,H13585-001!!
S!Q1L4!!!!FET_N_DUAL!!FET_N_DUAL_SMLF-2N7002DW,FET,D24280-001!!
S!Q1D1!!!!FET_N_DUAL!!FET_N_DUAL_SMLF-2N7002DW,FET,D24280-001!!
S!Q9P1!!!!FET_N_DUAL!!FET_N_DUAL_SMLF-2N7002DW,FET,D24280-001!!
S!R8A2!!DEFAULT_RESISTOR_2670OHM_2_1!!RES!!RES_0402-2.67K,1%,1/16W,CHIP,G21796-180!!
S!J8A2!!!!CONN36_G97614001!!CONN36_G97614001_CP-CONN,G97614-001!!
S!J8A1!!!!CONN72_G97614002_A!!CONN72_G97614002_A_CP-CONN,G97614-002!!
S!U7F1!!!!W25Q256!!W25Q256_XSOI-IC,H25002-001!!
S!U3T1!!!!W25Q256!!W25Q256_XSOI-IC,H25002-001!!
S!R1L8!!DEFAULT_RESISTOR_470.000000OHM_2_1!!RES!!RES_0402-470.0,5%,1/16W,CHIP,G21497-024!!
S!U2R1!!!!TTL2G14!!TTL2G14_SMLF-74LVC2G14,IC,D18476-001!!
S!U9A4!!!!TTL2G14!!TTL2G14_SMLF-74LVC2G14,IC,D18476-001!!
S!U9A3!!!!TTL2G14!!TTL2G14_SMLF-74LVC2G14,IC,D18476-001!!
S!RM1G1!!!!CAPTIVE_SCREW!!CAPTIVE_SCREW_TH-HDW,H57868-001!!
S!U8G1!!!!TTL2G07!!TTL2G07_SOT23LF-74LVC2G07,IC,D22707-001!!
S!U8F3!!!!TTL2G07!!TTL2G07_SOT23LF-74LVC2G07,IC,D22707-001!!
S!FB1U2!!DEFAULT_RESISTOR_60.000000OHM_2_1!!FERRITE!!FERRITE_SMLF-60,FB,693286-001!!
S!J8F1!!!!SCONN75K_H17033002!!SCONN75K_H17033002_SMT1-SCONN,H17033-002!!
S!U8D2!!!!TTL1G07_A!!TTL1G07_A_SOP-74LVC1G07,IC,C88419-001!!
S!U9A1!!!!TTL1G07_A!!TTL1G07_A_SOP-74LVC1G07,IC,C88419-001!!
S!U1L4!!!!TTL1G07_A!!TTL1G07_A_SOP-74LVC1G07,IC,C88419-001!!
S!U1R1!!!!TTL1G07_A!!TTL1G07_A_SOP-74LVC1G07,IC,C88419-001!!
S!U8D3!!!!TTL1G07_A!!TTL1G07_A_SOP-74LVC1G07,IC,C88419-001!!
S!U2P1!!!!TTL1G07_A!!TTL1G07_A_SOP-74LVC1G07,IC,C88419-001!!
S!U8G2!!!!TTL1G07_A!!TTL1G07_A_SOP-74LVC1G07,IC,C88419-001!!
S!U8G3!1!!!TTL1G07_A!!TTL1G07_A_SOP-74LVC1G07,IC,C88419-001!!
S!U9F3!!!!TTL1G07_A!!TTL1G07_A_SOP-74LVC1G07,IC,C88419-001!!
S!CR8E1!!!!DIODE!!DIODE_SMLF-BAT54WS,IC,C73510-001!!
S!CR7E1!!!!DIODE!!DIODE_SMLF-BAT54WS,IC,C73510-001!!
S!CR9P2!!!!DIODE!!DIODE_SMLF-BAT54WS,IC,C73510-001!!
S!CR9P1!!!!DIODE!!DIODE_SMLF-BAT54WS,IC,C73510-001!!
S!R1D40!!DEFAULT_RESISTOR_16.500000OHM_2_1!!RES!!RES_0402-40.2K,1%,1/16W,CHIP,G21796-133!!
S!R1L4!!DEFAULT_RESISTOR_40200OHM_2_1!!RES!!RES_0402-40.2K,1%,1/16W,CHIP,G21796-133!!
S!R1G23!!DEFAULT_RESISTOR_16000OHM_2_1!!RES!!RES_0402-4.02K,1%,1/16W,CHIP,G21796-082!!
S!R2L9!!DEFAULT_RESISTOR_16000OHM_2_1!!RES!!RES_0402-4.02K,1%,1/16W,CHIP,G21796-082!!
S!R3N22!!DEFAULT_RESISTOR_2670OHM_2_1!!RES!!RES_0402-4.02K,1%,1/16W,CHIP,G21796-082!!
S!R6P27!47!DEFAULT_RESISTOR_16000OHM_2_1!!RES!!RES_0402-4.02K,1%,1/16W,CHIP,G21796-082!!
S!R6P28!46!DEFAULT_RESISTOR_3160OHM_2_1!!RES!!RES_0402-4.02K,1%,1/16W,CHIP,G21796-082!!
S!R7G8!!DEFAULT_RESISTOR_16000OHM_2_1!!RES!!RES_0402-4.02K,1%,1/16W,CHIP,G21796-082!!
S!R9N8!!DEFAULT_RESISTOR_2260OHM_2_1!!RES!!RES_0402-4.02K,1%,1/16W,CHIP,G21796-082!!
S!R7C24!!!!RES!!RES_0402-4.02K,1%,1/16W,CHIP,G21796-082!!
S!R7A8!!DEFAULT_RESISTOR_4020OHM_2_1!!RES!!RES_0402-8.06K,1%,1/16W,CHIP,G21796-078!!
S!R7G10!!DEFAULT_RESISTOR_4020OHM_2_1!!RES!!RES_0402-8.06K,1%,1/16W,CHIP,G21796-078!!
S!R4C12!!!!RES!!RES_0402-8.06K,1%,1/16W,CHIP,G21796-078!!
S!C5G11!!!!CAP!!CAP_0603-22.0UF,4V,20%,X6S,E15431-004!!
S!C5G13!!!!CAP!!CAP_0603-22.0UF,4V,20%,X6S,E15431-004!!
S!C8U3!!!!CAP!!CAP_0603-22.0UF,4V,20%,X6S,E15431-004!!
S!C5G1!!!!CAP!!CAP_0603-22.0UF,4V,20%,X6S,E15431-004!!
S!C5G14!!!!CAP!!CAP_0603-22.0UF,4V,20%,X6S,E15431-004!!
S!C5A1!!!!CAP!!CAP_0603-22.0UF,4V,20%,X6S,E15431-004!!
S!C5A2!!!!CAP!!CAP_0603-22.0UF,4V,20%,X6S,E15431-004!!
S!C5A3!!!!CAP!!CAP_0603-22.0UF,4V,20%,X6S,E15431-004!!
S!C5A4!!!!CAP!!CAP_0603-22.0UF,4V,20%,X6S,E15431-004!!
S!C8U7!!!!CAP!!CAP_0603-22.0UF,4V,20%,X6S,E15431-004!!
S!C8U6!!!!CAP!!CAP_0603-22.0UF,4V,20%,X6S,E15431-004!!
S!C8U5!!!!CAP!!CAP_0603-22.0UF,4V,20%,X6S,E15431-004!!
S!C8M1!!!!CAP!!CAP_0603-22.0UF,4V,20%,X6S,E15431-004!!
S!C7L4!!!!CAP!!CAP_0603-22.0UF,4V,20%,X6S,E15431-004!!
S!C2A4!!!!CAP!!CAP_0603-22.0UF,4V,20%,X6S,E15431-004!!
S!C2A3!!!!CAP!!CAP_0603-22.0UF,4V,20%,X6S,E15431-004!!
S!C5G12!!!!CAP!!CAP_0603-22.0UF,4V,20%,X6S,E15431-004!!
S!C5G2!!!!CAP!!CAP_0603-22.0UF,4V,20%,X6S,E15431-004!!
S!C5G4!!!!CAP!!CAP_0603-22.0UF,4V,20%,X6S,E15431-004!!
S!C5G6!!!!CAP!!CAP_0603-22.0UF,4V,20%,X6S,E15431-004!!
S!C5G5!!!!CAP!!CAP_0603-22.0UF,4V,20%,X6S,E15431-004!!
S!C5G7!!!!CAP!!CAP_0603-22.0UF,4V,20%,X6S,E15431-004!!
S!C5G8!!!!CAP!!CAP_0603-22.0UF,4V,20%,X6S,E15431-004!!
S!C5G18!!!!CAP!!CAP_0603-22.0UF,4V,20%,X6S,E15431-004!!
S!C5G17!!!!CAP!!CAP_0603-22.0UF,4V,20%,X6S,E15431-004!!
S!C5G16!!!!CAP!!CAP_0603-22.0UF,4V,20%,X6S,E15431-004!!
S!C5G15!!!!CAP!!CAP_0603-22.0UF,4V,20%,X6S,E15431-004!!
S!C5G3!!!!CAP!!CAP_0603-22.0UF,4V,20%,X6S,E15431-004!!
S!C5A15!!!!CAP!!CAP_0603-22.0UF,4V,20%,X6S,E15431-004!!
S!C5A12!!!!CAP!!CAP_0603-22.0UF,4V,20%,X6S,E15431-004!!
S!C5A13!!!!CAP!!CAP_0603-22.0UF,4V,20%,X6S,E15431-004!!
S!C5A14!!!!CAP!!CAP_0603-22.0UF,4V,20%,X6S,E15431-004!!
S!C5A6!!!!CAP!!CAP_0603-22.0UF,4V,20%,X6S,E15431-004!!
S!C5A7!!!!CAP!!CAP_0603-22.0UF,4V,20%,X6S,E15431-004!!
S!C5A8!!!!CAP!!CAP_0603-22.0UF,4V,20%,X6S,E15431-004!!
S!C5A9!!!!CAP!!CAP_0603-22.0UF,4V,20%,X6S,E15431-004!!
S!C5A16!!!!CAP!!CAP_0603-22.0UF,4V,20%,X6S,E15431-004!!
S!C5A17!!!!CAP!!CAP_0603-22.0UF,4V,20%,X6S,E15431-004!!
S!C5A18!!!!CAP!!CAP_0603-22.0UF,4V,20%,X6S,E15431-004!!
S!C5A19!!!!CAP!!CAP_0603-22.0UF,4V,20%,X6S,E15431-004!!
S!C8U2!!!!CAP!!CAP_0603-22.0UF,4V,20%,X6S,E15431-004!!
S!C7U2!!!!CAP!!CAP_0603-22.0UF,4V,20%,X6S,E15431-004!!
S!C7U1!!!!CAP!!CAP_0603-22.0UF,4V,20%,X6S,E15431-004!!
S!C7T4!!!!CAP!!CAP_0603-22.0UF,4V,20%,X6S,E15431-004!!
S!C7T5!!!!CAP!!CAP_0603-22.0UF,4V,20%,X6S,E15431-004!!
S!C8T5!!!!CAP!!CAP_0603-22.0UF,4V,20%,X6S,E15431-004!!
S!C8T6!!!!CAP!!CAP_0603-22.0UF,4V,20%,X6S,E15431-004!!
S!C8T7!!!!CAP!!CAP_0603-22.0UF,4V,20%,X6S,E15431-004!!
S!C8T8!!!!CAP!!CAP_0603-22.0UF,4V,20%,X6S,E15431-004!!
S!C8T9!!!!CAP!!CAP_0603-22.0UF,4V,20%,X6S,E15431-004!!
S!C8T10!!!!CAP!!CAP_0603-22.0UF,4V,20%,X6S,E15431-004!!
S!C8U4!!!!CAP!!CAP_0603-22.0UF,4V,20%,X6S,E15431-004!!
S!C8L5!!!!CAP!!CAP_0603-22.0UF,4V,20%,X6S,E15431-004!!
S!C8L6!!!!CAP!!CAP_0603-22.0UF,4V,20%,X6S,E15431-004!!
S!C8L7!!!!CAP!!CAP_0603-22.0UF,4V,20%,X6S,E15431-004!!
S!C8L8!!!!CAP!!CAP_0603-22.0UF,4V,20%,X6S,E15431-004!!
S!C8L9!!!!CAP!!CAP_0603-22.0UF,4V,20%,X6S,E15431-004!!
S!C8M6!!!!CAP!!CAP_0603-22.0UF,4V,20%,X6S,E15431-004!!
S!C8M4!!!!CAP!!CAP_0603-22.0UF,4V,20%,X6S,E15431-004!!
S!C7M2!!!!CAP!!CAP_0603-22.0UF,4V,20%,X6S,E15431-004!!
S!C7M1!!!!CAP!!CAP_0603-22.0UF,4V,20%,X6S,E15431-004!!
S!C8L10!!!!CAP!!CAP_0603-22.0UF,4V,20%,X6S,E15431-004!!
S!C8M5!!!!CAP!!CAP_0603-22.0UF,4V,20%,X6S,E15431-004!!
S!C8M3!!!!CAP!!CAP_0603-22.0UF,4V,20%,X6S,E15431-004!!
S!C2G9!!!!CAP!!CAP_0603-22.0UF,4V,20%,X6S,E15431-004!!
S!C2G10!!!!CAP!!CAP_0603-22.0UF,4V,20%,X6S,E15431-004!!
S!C2G11!!!!CAP!!CAP_0603-22.0UF,4V,20%,X6S,E15431-004!!
S!C2G12!!!!CAP!!CAP_0603-22.0UF,4V,20%,X6S,E15431-004!!
S!C2G1!!!!CAP!!CAP_0603-22.0UF,4V,20%,X6S,E15431-004!!
S!C2G2!!!!CAP!!CAP_0603-22.0UF,4V,20%,X6S,E15431-004!!
S!C2G3!!!!CAP!!CAP_0603-22.0UF,4V,20%,X6S,E15431-004!!
S!C2G4!!!!CAP!!CAP_0603-22.0UF,4V,20%,X6S,E15431-004!!
S!C2G5!!!!CAP!!CAP_0603-22.0UF,4V,20%,X6S,E15431-004!!
S!C2G6!!!!CAP!!CAP_0603-22.0UF,4V,20%,X6S,E15431-004!!
S!C3G1!!!!CAP!!CAP_0603-22.0UF,4V,20%,X6S,E15431-004!!
S!C3G2!!!!CAP!!CAP_0603-22.0UF,4V,20%,X6S,E15431-004!!
S!C2G13!!!!CAP!!CAP_0603-22.0UF,4V,20%,X6S,E15431-004!!
S!C2G14!!!!CAP!!CAP_0603-22.0UF,4V,20%,X6S,E15431-004!!
S!C3G5!!!!CAP!!CAP_0603-22.0UF,4V,20%,X6S,E15431-004!!
S!C3G6!!!!CAP!!CAP_0603-22.0UF,4V,20%,X6S,E15431-004!!
S!C7L5!!!!CAP!!CAP_0603-22.0UF,4V,20%,X6S,E15431-004!!
S!C3A6!!!!CAP!!CAP_0603-22.0UF,4V,20%,X6S,E15431-004!!
S!C3A5!!!!CAP!!CAP_0603-22.0UF,4V,20%,X6S,E15431-004!!
S!C2A15!!!!CAP!!CAP_0603-22.0UF,4V,20%,X6S,E15431-004!!
S!C2A14!!!!CAP!!CAP_0603-22.0UF,4V,20%,X6S,E15431-004!!
S!C2A6!!!!CAP!!CAP_0603-22.0UF,4V,20%,X6S,E15431-004!!
S!C2A7!!!!CAP!!CAP_0603-22.0UF,4V,20%,X6S,E15431-004!!
S!C3A1!!!!CAP!!CAP_0603-22.0UF,4V,20%,X6S,E15431-004!!
S!C3A2!!!!CAP!!CAP_0603-22.0UF,4V,20%,X6S,E15431-004!!
S!C2A9!!!!CAP!!CAP_0603-22.0UF,4V,20%,X6S,E15431-004!!
S!C2A10!!!!CAP!!CAP_0603-22.0UF,4V,20%,X6S,E15431-004!!
S!C2A11!!!!CAP!!CAP_0603-22.0UF,4V,20%,X6S,E15431-004!!
S!C2A13!!!!CAP!!CAP_0603-22.0UF,4V,20%,X6S,E15431-004!!
S!C2A12!!!!CAP!!CAP_0603-22.0UF,4V,20%,X6S,E15431-004!!
S!C2A1!!!!CAP!!CAP_0603-22.0UF,4V,20%,X6S,E15431-004!!
S!C2A2!!!!CAP!!CAP_0603-22.0UF,4V,20%,X6S,E15431-004!!
S!C5U2!!!!CAP!!CAP_0603-22.0UF,4V,20%,X6S,E15431-004!!
S!C5U3!!!!CAP!!CAP_0603-22.0UF,4V,20%,X6S,E15431-004!!
S!C5U4!!!!CAP!!CAP_0603-22.0UF,4V,20%,X6S,E15431-004!!
S!C5U5!!!!CAP!!CAP_0603-22.0UF,4V,20%,X6S,E15431-004!!
S!C5U6!!!!CAP!!CAP_0603-22.0UF,4V,20%,X6S,E15431-004!!
S!C5U7!!!!CAP!!CAP_0603-22.0UF,4V,20%,X6S,E15431-004!!
S!C5U8!!!!CAP!!CAP_0603-22.0UF,4V,20%,X6S,E15431-004!!
S!C5U9!!!!CAP!!CAP_0603-22.0UF,4V,20%,X6S,E15431-004!!
S!C5T12!!!!CAP!!CAP_0603-22.0UF,4V,20%,X6S,E15431-004!!
S!C5T11!!!!CAP!!CAP_0603-22.0UF,4V,20%,X6S,E15431-004!!
S!C5T10!!!!CAP!!CAP_0603-22.0UF,4V,20%,X6S,E15431-004!!
S!C5T9!!!!CAP!!CAP_0603-22.0UF,4V,20%,X6S,E15431-004!!
S!C5T8!!!!CAP!!CAP_0603-22.0UF,4V,20%,X6S,E15431-004!!
S!C5T7!!!!CAP!!CAP_0603-22.0UF,4V,20%,X6S,E15431-004!!
S!C5T6!!!!CAP!!CAP_0603-22.0UF,4V,20%,X6S,E15431-004!!
S!C5T5!!!!CAP!!CAP_0603-22.0UF,4V,20%,X6S,E15431-004!!
S!C5L6!!!!CAP!!CAP_0603-22.0UF,4V,20%,X6S,E15431-004!!
S!C5L7!!!!CAP!!CAP_0603-22.0UF,4V,20%,X6S,E15431-004!!
S!C5L8!!!!CAP!!CAP_0603-22.0UF,4V,20%,X6S,E15431-004!!
S!C5L9!!!!CAP!!CAP_0603-22.0UF,4V,20%,X6S,E15431-004!!
S!C5L10!!!!CAP!!CAP_0603-22.0UF,4V,20%,X6S,E15431-004!!
S!C5L11!!!!CAP!!CAP_0603-22.0UF,4V,20%,X6S,E15431-004!!
S!C5L12!!!!CAP!!CAP_0603-22.0UF,4V,20%,X6S,E15431-004!!
S!C5L13!!!!CAP!!CAP_0603-22.0UF,4V,20%,X6S,E15431-004!!
S!C5M7!!!!CAP!!CAP_0603-22.0UF,4V,20%,X6S,E15431-004!!
S!C5M6!!!!CAP!!CAP_0603-22.0UF,4V,20%,X6S,E15431-004!!
S!C5M5!!!!CAP!!CAP_0603-22.0UF,4V,20%,X6S,E15431-004!!
S!C5M4!!!!CAP!!CAP_0603-22.0UF,4V,20%,X6S,E15431-004!!
S!C5M2!!!!CAP!!CAP_0603-22.0UF,4V,20%,X6S,E15431-004!!
S!C5M1!!!!CAP!!CAP_0603-22.0UF,4V,20%,X6S,E15431-004!!
S!C4M2!!!!CAP!!CAP_0603-22.0UF,4V,20%,X6S,E15431-004!!
S!C5A11!!!!CAP!!CAP_0603-22.0UF,4V,20%,X6S,E15431-004!!
S!C5D44!109!DEFAULT_CAPACITOR_1e+07pF_2_1!!CAP!!CAP_0603-22.0UF,4V,20%,X6S,E15431-004!!
S!C5D4!128!DEFAULT_CAPACITOR_1e+07pF_2_1!!CAP!!CAP_0603-22.0UF,4V,20%,X6S,E15431-004!!
S!C5D3!110!DEFAULT_CAPACITOR_1e+07pF_2_1!!CAP!!CAP_0603-22.0UF,4V,20%,X6S,E15431-004!!
S!C5D2!111!DEFAULT_CAPACITOR_1e+07pF_2_1!!CAP!!CAP_0603-22.0UF,4V,20%,X6S,E15431-004!!
S!C5D1!129!DEFAULT_CAPACITOR_1e+07pF_2_1!!CAP!!CAP_0603-22.0UF,4V,20%,X6S,E15431-004!!
S!C5D59!112!DEFAULT_CAPACITOR_1e+07pF_2_1!!CAP!!CAP_0603-22.0UF,4V,20%,X6S,E15431-004!!
S!C5D42!130!DEFAULT_CAPACITOR_1e+07pF_2_1!!CAP!!CAP_0603-22.0UF,4V,20%,X6S,E15431-004!!
S!C5D5!113!DEFAULT_CAPACITOR_1e+07pF_2_1!!CAP!!CAP_0603-22.0UF,4V,20%,X6S,E15431-004!!
S!C5D19!114!DEFAULT_CAPACITOR_1e+07pF_2_1!!CAP!!CAP_0603-22.0UF,4V,20%,X6S,E15431-004!!
S!C5D18!131!DEFAULT_CAPACITOR_1e+07pF_2_1!!CAP!!CAP_0603-22.0UF,4V,20%,X6S,E15431-004!!
S!C5D17!115!DEFAULT_CAPACITOR_1e+07pF_2_1!!CAP!!CAP_0603-22.0UF,4V,20%,X6S,E15431-004!!
S!C5D16!116!DEFAULT_CAPACITOR_1e+07pF_2_1!!CAP!!CAP_0603-22.0UF,4V,20%,X6S,E15431-004!!
S!C5D15!175!DEFAULT_CAPACITOR_1e+07pF_2_1!!CAP!!CAP_0603-22.0UF,4V,20%,X6S,E15431-004!!
S!C5D14!176!DEFAULT_CAPACITOR_1e+07pF_2_1!!CAP!!CAP_0603-22.0UF,4V,20%,X6S,E15431-004!!
S!C5D58!198!DEFAULT_CAPACITOR_1e+07pF_2_1!!CAP!!CAP_0603-22.0UF,4V,20%,X6S,E15431-004!!
S!C5D43!217!DEFAULT_CAPACITOR_1e+07pF_2_1!!CAP!!CAP_0603-22.0UF,4V,20%,X6S,E15431-004!!
S!C5D60!177!DEFAULT_CAPACITOR_1e+07pF_2_1!!CAP!!CAP_0603-22.0UF,4V,20%,X6S,E15431-004!!
S!C5D32!199!DEFAULT_CAPACITOR_1e+07pF_2_1!!CAP!!CAP_0603-22.0UF,4V,20%,X6S,E15431-004!!
S!C5D31!200!DEFAULT_CAPACITOR_1e+07pF_2_1!!CAP!!CAP_0603-22.0UF,4V,20%,X6S,E15431-004!!
S!C5D30!178!DEFAULT_CAPACITOR_1e+07pF_2_1!!CAP!!CAP_0603-22.0UF,4V,20%,X6S,E15431-004!!
S!C5D29!201!DEFAULT_CAPACITOR_1e+07pF_2_1!!CAP!!CAP_0603-22.0UF,4V,20%,X6S,E15431-004!!
S!C5D26!202!DEFAULT_CAPACITOR_1e+07pF_2_1!!CAP!!CAP_0603-22.0UF,4V,20%,X6S,E15431-004!!
S!C5D24!132!DEFAULT_CAPACITOR_1e+07pF_2_1!!CAP!!CAP_0603-22.0UF,4V,20%,X6S,E15431-004!!
S!C5D39!117!DEFAULT_CAPACITOR_1e+07pF_2_1!!CAP!!CAP_0603-22.0UF,4V,20%,X6S,E15431-004!!
S!C5D40!180!DEFAULT_CAPACITOR_1e+07pF_2_1!!CAP!!CAP_0603-22.0UF,4V,20%,X6S,E15431-004!!
S!C5D41!205!DEFAULT_CAPACITOR_1e+07pF_2_1!!CAP!!CAP_0603-22.0UF,4V,20%,X6S,E15431-004!!
S!C5D61!181!DEFAULT_CAPACITOR_1e+07pF_2_1!!CAP!!CAP_0603-22.0UF,4V,20%,X6S,E15431-004!!
S!C5D47!182!DEFAULT_CAPACITOR_1e+07pF_2_1!!CAP!!CAP_0603-22.0UF,4V,20%,X6S,E15431-004!!
S!C5D46!206!DEFAULT_CAPACITOR_1e+07pF_2_1!!CAP!!CAP_0603-22.0UF,4V,20%,X6S,E15431-004!!
S!C3D10!!DEFAULT_CAPACITOR_1e+07pF_2_1!!CAP!!CAP_0603-22.0UF,4V,20%,X6S,E15431-004!!
S!C2D34!!DEFAULT_CAPACITOR_1e+07pF_2_1!!CAP!!CAP_0603-22.0UF,4V,20%,X6S,E15431-004!!
S!C2D16!!DEFAULT_CAPACITOR_1e+07pF_2_1!!CAP!!CAP_0603-22.0UF,4V,20%,X6S,E15431-004!!
S!C2D36!!DEFAULT_CAPACITOR_1e+07pF_2_1!!CAP!!CAP_0603-22.0UF,4V,20%,X6S,E15431-004!!
S!C2D37!!DEFAULT_CAPACITOR_1e+07pF_2_1!!CAP!!CAP_0603-22.0UF,4V,20%,X6S,E15431-004!!
S!C2D45!!DEFAULT_CAPACITOR_1e+07pF_2_1!!CAP!!CAP_0603-22.0UF,4V,20%,X6S,E15431-004!!
S!C3D2!!DEFAULT_CAPACITOR_1e+07pF_2_1!!CAP!!CAP_0603-22.0UF,4V,20%,X6S,E15431-004!!
S!C3D1!!DEFAULT_CAPACITOR_1e+07pF_2_1!!CAP!!CAP_0603-22.0UF,4V,20%,X6S,E15431-004!!
S!C2D1!!DEFAULT_CAPACITOR_1e+07pF_2_1!!CAP!!CAP_0603-22.0UF,4V,20%,X6S,E15431-004!!
S!C2D18!!DEFAULT_CAPACITOR_1e+07pF_2_1!!CAP!!CAP_0603-22.0UF,4V,20%,X6S,E15431-004!!
S!C2D17!!DEFAULT_CAPACITOR_1e+07pF_2_1!!CAP!!CAP_0603-22.0UF,4V,20%,X6S,E15431-004!!
S!C2D27!!DEFAULT_CAPACITOR_1e+07pF_2_1!!CAP!!CAP_0603-22.0UF,4V,20%,X6S,E15431-004!!
S!C2D26!!DEFAULT_CAPACITOR_1e+07pF_2_1!!CAP!!CAP_0603-22.0UF,4V,20%,X6S,E15431-004!!
S!C2D23!!DEFAULT_CAPACITOR_1e+07pF_2_1!!CAP!!CAP_0603-22.0UF,4V,20%,X6S,E15431-004!!
S!C2D21!!DEFAULT_CAPACITOR_1e+07pF_2_1!!CAP!!CAP_0603-22.0UF,4V,20%,X6S,E15431-004!!
S!C2D33!!DEFAULT_CAPACITOR_1e+07pF_2_1!!CAP!!CAP_0603-22.0UF,4V,20%,X6S,E15431-004!!
S!C2D32!!DEFAULT_CAPACITOR_1e+07pF_2_1!!CAP!!CAP_0603-22.0UF,4V,20%,X6S,E15431-004!!
S!C2D31!!DEFAULT_CAPACITOR_1e+07pF_2_1!!CAP!!CAP_0603-22.0UF,4V,20%,X6S,E15431-004!!
S!C2D30!!DEFAULT_CAPACITOR_1e+07pF_2_1!!CAP!!CAP_0603-22.0UF,4V,20%,X6S,E15431-004!!
S!C2D29!!DEFAULT_CAPACITOR_1e+07pF_2_1!!CAP!!CAP_0603-22.0UF,4V,20%,X6S,E15431-004!!
S!C2D28!!DEFAULT_CAPACITOR_1e+07pF_2_1!!CAP!!CAP_0603-22.0UF,4V,20%,X6S,E15431-004!!
S!C2D25!!DEFAULT_CAPACITOR_1e+07pF_2_1!!CAP!!CAP_0603-22.0UF,4V,20%,X6S,E15431-004!!
S!C2D24!!DEFAULT_CAPACITOR_1e+07pF_2_1!!CAP!!CAP_0603-22.0UF,4V,20%,X6S,E15431-004!!
S!C2D22!!DEFAULT_CAPACITOR_1e+07pF_2_1!!CAP!!CAP_0603-22.0UF,4V,20%,X6S,E15431-004!!
S!C2D19!!DEFAULT_CAPACITOR_1e+07pF_2_1!!CAP!!CAP_0603-22.0UF,4V,20%,X6S,E15431-004!!
S!C2D20!!DEFAULT_CAPACITOR_1e+07pF_2_1!!CAP!!CAP_0603-22.0UF,4V,20%,X6S,E15431-004!!
S!C2D12!!DEFAULT_CAPACITOR_1e+07pF_2_1!!CAP!!CAP_0603-22.0UF,4V,20%,X6S,E15431-004!!
S!C2D15!!DEFAULT_CAPACITOR_1e+07pF_2_1!!CAP!!CAP_0603-22.0UF,4V,20%,X6S,E15431-004!!
S!C3E1!281!DEFAULT_CAPACITOR_2.2e+07pF_2_1!!CAP!!CAP_0603-22.0UF,4V,20%,X6S,E15431-004!!
S!C7C6!427!DEFAULT_CAPACITOR_2.2e+07pF_2_1!!CAP!!CAP_0603-22.0UF,4V,20%,X6S,E15431-004!!
S!C7R1!372!DEFAULT_CAPACITOR_2.2e+07pF_2_1!!CAP!!CAP_0603-22.0UF,4V,20%,X6S,E15431-004!!
S!C7C10!!DEFAULT_CAPACITOR_2.2e+07pF_2_1!!CAP!!CAP_0603-22.0UF,4V,20%,X6S,E15431-004!!
S!C4E11!114!DEFAULT_CAPACITOR_2.2e+07pF_2_1!!CAP!!CAP_0603-22.0UF,4V,20%,X6S,E15431-004!!
S!C4D12!115!DEFAULT_CAPACITOR_2.2e+07pF_2_1!!CAP!!CAP_0603-22.0UF,4V,20%,X6S,E15431-004!!
S!C6N7!!DEFAULT_CAPACITOR_2.2e+07pF_2_1!!CAP!!CAP_0603-22.0UF,4V,20%,X6S,E15431-004!!
S!C6R7!113!DEFAULT_CAPACITOR_2.2e+07pF_2_1!!CAP!!CAP_0603-22.0UF,4V,20%,X6S,E15431-004!!
S!C9R8!!DEFAULT_CAPACITOR_2.2e+07pF_2_1!!CAP!!CAP_0603-22.0UF,4V,20%,X6S,E15431-004!!
S!C1E3!!DEFAULT_CAPACITOR_2.2e+07pF_2_1!!CAP!!CAP_0603-22.0UF,4V,20%,X6S,E15431-004!!
S!C1D14!!DEFAULT_CAPACITOR_2.2e+07pF_2_1!!CAP!!CAP_0603-22.0UF,4V,20%,X6S,E15431-004!!
S!C1D3!!DEFAULT_CAPACITOR_2.2e+07pF_2_1!!CAP!!CAP_0603-22.0UF,4V,20%,X6S,E15431-004!!
S!C1C19!!DEFAULT_CAPACITOR_2.2e+07pF_2_1!!CAP!!CAP_0603-22.0UF,4V,20%,X6S,E15431-004!!
S!C6P3!!DEFAULT_CAPACITOR_2.2e+07pF_2_1!!CAP!!CAP_0603-22.0UF,4V,20%,X6S,E15431-004!!
S!C1D24!!DEFAULT_CAPACITOR_2.2e+07pF_2_1!!CAP!!CAP_0603-22.0UF,4V,20%,X6S,E15431-004!!
S!C6P21!!DEFAULT_CAPACITOR_2.2e+07pF_2_1!!CAP!!CAP_0603-22.0UF,4V,20%,X6S,E15431-004!!
S!C6P16!!DEFAULT_CAPACITOR_2.2e+07pF_2_1!!CAP!!CAP_0603-22.0UF,4V,20%,X6S,E15431-004!!
S!C4E3!!DEFAULT_CAPACITOR_2.2e+07pF_2_1!!CAP!!CAP_0603-22.0UF,4V,20%,X6S,E15431-004!!
S!C4D34!!DEFAULT_CAPACITOR_2.2e+07pF_2_1!!CAP!!CAP_0603-22.0UF,4V,20%,X6S,E15431-004!!
S!C4D4!!DEFAULT_CAPACITOR_2.2e+07pF_2_1!!CAP!!CAP_0603-22.0UF,4V,20%,X6S,E15431-004!!
S!C6R2!!DEFAULT_CAPACITOR_2.2e+07pF_2_1!!CAP!!CAP_0603-22.0UF,4V,20%,X6S,E15431-004!!
S!C4C11!!DEFAULT_CAPACITOR_2.2e+07pF_2_1!!CAP!!CAP_0603-22.0UF,4V,20%,X6S,E15431-004!!
S!C9P3!!DEFAULT_CAPACITOR_2.2e+07pF_2_1!!CAP!!CAP_0603-22.0UF,4V,20%,X6S,E15431-004!!
S!C1E9!!DEFAULT_CAPACITOR_2.2e+07pF_2_1!!CAP!!CAP_0603-22.0UF,4V,20%,X6S,E15431-004!!
S!C9R2!!DEFAULT_CAPACITOR_2.2e+07pF_2_1!!CAP!!CAP_0603-22.0UF,4V,20%,X6S,E15431-004!!
S!C9P10!!DEFAULT_CAPACITOR_2.2e+07pF_2_1!!CAP!!CAP_0603-22.0UF,4V,20%,X6S,E15431-004!!
S!C9P20!!DEFAULT_CAPACITOR_2.2e+07pF_2_1!!CAP!!CAP_0603-22.0UF,4V,20%,X6S,E15431-004!!
S!C9N22!!DEFAULT_CAPACITOR_2.2e+07pF_2_1!!CAP!!CAP_0603-22.0UF,4V,20%,X6S,E15431-004!!
S!C3D19!!DEFAULT_CAPACITOR_4.7e+07pF_2_1!!CAP!!CAP_0603-22.0UF,4V,20%,X6S,E15431-004!!
S!C5D52!!DEFAULT_CAPACITOR_4.7e+07pF_2_1!!CAP!!CAP_0603-22.0UF,4V,20%,X6S,E15431-004!!
S!C5D33!!!!CAP!!CAP_0603-22.0UF,4V,20%,X6S,E15431-004!!
S!C5D34!!!!CAP!!CAP_0603-22.0UF,4V,20%,X6S,E15431-004!!
S!C5D53!!!!CAP!!CAP_0603-22.0UF,4V,20%,X6S,E15431-004!!
S!C2D3!!!!CAP!!CAP_0603-22.0UF,4V,20%,X6S,E15431-004!!
S!C2D2!!!!CAP!!CAP_0603-22.0UF,4V,20%,X6S,E15431-004!!
S!C3D20!!!!CAP!!CAP_0603-22.0UF,4V,20%,X6S,E15431-004!!
S!C5D20!195!DEFAULT_CAPACITOR_2.2e+07pF_2_1!!CAP!!CAP_0603-22.0UF,4V,20%,X6S,E15431-004!!
S!C5D28!218!DEFAULT_CAPACITOR_1e+07pF_2_1!!CAP!!CAP_0603-22.0UF,4V,20%,X6S,E15431-004!!
S!C5D27!179!DEFAULT_CAPACITOR_1e+07pF_2_1!!CAP!!CAP_0603-22.0UF,4V,20%,X6S,E15431-004!!
S!C5D35!104!DEFAULT_CAPACITOR_2.2e+07pF_2_1!!CAP!!CAP_0603-22.0UF,4V,20%,X6S,E15431-004!!
S!C5D25!203!DEFAULT_CAPACITOR_1e+07pF_2_1!!CAP!!CAP_0603-22.0UF,4V,20%,X6S,E15431-004!!
S!C5D45!207!DEFAULT_CAPACITOR_1e+07pF_2_1!!CAP!!CAP_0603-22.0UF,4V,20%,X6S,E15431-004!!
S!C2D46!!DEFAULT_CAPACITOR_2.2e+07pF_2_1!!CAP!!CAP_0603-22.0UF,4V,20%,X6S,E15431-004!!
S!C2D13!!DEFAULT_CAPACITOR_1e+07pF_2_1!!CAP!!CAP_0603-22.0UF,4V,20%,X6S,E15431-004!!
S!C2D14!!DEFAULT_CAPACITOR_1e+07pF_2_1!!CAP!!CAP_0603-22.0UF,4V,20%,X6S,E15431-004!!
S!C2D47!!DEFAULT_CAPACITOR_2.2e+07pF_2_1!!CAP!!CAP_0603-22.0UF,4V,20%,X6S,E15431-004!!
S!C2D38!!DEFAULT_CAPACITOR_1e+07pF_2_1!!CAP!!CAP_0603-22.0UF,4V,20%,X6S,E15431-004!!
S!C3D25!!DEFAULT_CAPACITOR_2.2e+07pF_2_1!!CAP!!CAP_0603-22.0UF,4V,20%,X6S,E15431-004!!
S!C2D35!!DEFAULT_CAPACITOR_1e+07pF_2_1!!CAP!!CAP_0603-22.0UF,4V,20%,X6S,E15431-004!!
S!C7P12!!DEFAULT_CAPACITOR_1e+07pF_2_1!!CAP!!CAP_0603-22.0UF,4V,20%,X6S,E15431-004!!
S!C5D48!159!DEFAULT_CAPACITOR_1e+07pF_2_1!!CAP!!CAP_0603-22.0UF,4V,20%,X6S,E15431-004!!
S!C6D8!204!DEFAULT_CAPACITOR_1e+07pF_2_1!!CAP!!CAP_0603-22.0UF,4V,20%,X6S,E15431-004!!
S!C5D50!160!DEFAULT_CAPACITOR_1e+07pF_2_1!!CAP!!CAP_0603-22.0UF,4V,20%,X6S,E15431-004!!
S!C5D36!208!DEFAULT_CAPACITOR_1e+07pF_2_1!!CAP!!CAP_0603-22.0UF,4V,20%,X6S,E15431-004!!
S!C5D21!161!DEFAULT_CAPACITOR_1e+07pF_2_1!!CAP!!CAP_0603-22.0UF,4V,20%,X6S,E15431-004!!
S!C5D49!209!DEFAULT_CAPACITOR_1e+07pF_2_1!!CAP!!CAP_0603-22.0UF,4V,20%,X6S,E15431-004!!
S!C5D51!162!DEFAULT_CAPACITOR_1e+07pF_2_1!!CAP!!CAP_0603-22.0UF,4V,20%,X6S,E15431-004!!
S!C6D2!219!DEFAULT_CAPACITOR_1e+07pF_2_1!!CAP!!CAP_0603-22.0UF,4V,20%,X6S,E15431-004!!
S!C6D5!220!DEFAULT_CAPACITOR_1e+07pF_2_1!!CAP!!CAP_0603-22.0UF,4V,20%,X6S,E15431-004!!
S!C5D37!221!DEFAULT_CAPACITOR_1e+07pF_2_1!!CAP!!CAP_0603-22.0UF,4V,20%,X6S,E15431-004!!
S!C5D38!170!DEFAULT_CAPACITOR_1e+07pF_2_1!!CAP!!CAP_0603-22.0UF,4V,20%,X6S,E15431-004!!
S!C2D39!!DEFAULT_CAPACITOR_1e+07pF_2_1!!CAP!!CAP_0603-22.0UF,4V,20%,X6S,E15431-004!!
S!C3D17!!DEFAULT_CAPACITOR_1e+07pF_2_1!!CAP!!CAP_0603-22.0UF,4V,20%,X6S,E15431-004!!
S!C3D18!!DEFAULT_CAPACITOR_1e+07pF_2_1!!CAP!!CAP_0603-22.0UF,4V,20%,X6S,E15431-004!!
S!C2D40!!DEFAULT_CAPACITOR_1e+07pF_2_1!!CAP!!CAP_0603-22.0UF,4V,20%,X6S,E15431-004!!
S!C3D14!!DEFAULT_CAPACITOR_1e+07pF_2_1!!CAP!!CAP_0603-22.0UF,4V,20%,X6S,E15431-004!!
S!C3D13!!DEFAULT_CAPACITOR_1e+07pF_2_1!!CAP!!CAP_0603-22.0UF,4V,20%,X6S,E15431-004!!
S!C3D6!!DEFAULT_CAPACITOR_1e+07pF_2_1!!CAP!!CAP_0603-22.0UF,4V,20%,X6S,E15431-004!!
S!C3D11!!DEFAULT_CAPACITOR_1e+07pF_2_1!!CAP!!CAP_0603-22.0UF,4V,20%,X6S,E15431-004!!
S!C3D4!!DEFAULT_CAPACITOR_1e+07pF_2_1!!CAP!!CAP_0603-22.0UF,4V,20%,X6S,E15431-004!!
S!C3D16!!DEFAULT_CAPACITOR_1e+07pF_2_1!!CAP!!CAP_0603-22.0UF,4V,20%,X6S,E15431-004!!
S!C3D12!!DEFAULT_CAPACITOR_1e+07pF_2_1!!CAP!!CAP_0603-22.0UF,4V,20%,X6S,E15431-004!!
S!C3D8!!DEFAULT_CAPACITOR_1e+07pF_2_1!!CAP!!CAP_0603-22.0UF,4V,20%,X6S,E15431-004!!
S!C3D5!!DEFAULT_CAPACITOR_1e+07pF_2_1!!CAP!!CAP_0603-22.0UF,4V,20%,X6S,E15431-004!!
S!C3D9!!DEFAULT_CAPACITOR_1e+07pF_2_1!!CAP!!CAP_0603-22.0UF,4V,20%,X6S,E15431-004!!
S!C3D21!!DEFAULT_CAPACITOR_1e+07pF_2_1!!CAP!!CAP_0603-22.0UF,4V,20%,X6S,E15431-004!!
S!C5D22!!DEFAULT_CAPACITOR_2.2e+07pF_2_1!!CAP!!CAP_0603-22.0UF,4V,20%,X6S,E15431-004!!
S!C3D23!!DEFAULT_CAPACITOR_2.2e+07pF_2_1!!CAP!!CAP_0603-22.0UF,4V,20%,X6S,E15431-004!!
S!C7P16!!DEFAULT_CAPACITOR_2.2e+07pF_2_1!!CAP!!CAP_0603-22.0UF,4V,20%,X6S,E15431-004!!
S!C3D15!!DEFAULT_CAPACITOR_2.2e+07pF_2_1!!CAP!!CAP_0603-22.0UF,4V,20%,X6S,E15431-004!!
S!C4P8!!DEFAULT_CAPACITOR_2.2e+07pF_2_1!!CAP!!CAP_0603-22.0UF,4V,20%,X6S,E15431-004!!
S!C6D10!!DEFAULT_CAPACITOR_2.2e+07pF_2_1!!CAP!!CAP_0603-22.0UF,4V,20%,X6S,E15431-004!!
S!C6D9!!DEFAULT_CAPACITOR_2.2e+07pF_2_1!!CAP!!CAP_0603-22.0UF,4V,20%,X6S,E15431-004!!
S!C4P6!!DEFAULT_CAPACITOR_2.2e+07pF_2_1!!CAP!!CAP_0603-22.0UF,4V,20%,X6S,E15431-004!!
S!C3D7!!DEFAULT_CAPACITOR_2.2e+07pF_2_1!!CAP!!CAP_0603-22.0UF,4V,20%,X6S,E15431-004!!
S!C5D23!158!DEFAULT_CAPACITOR_1e+07pF_2_1!!CAP!!CAP_0603-22.0UF,4V,20%,X6S,E15431-004!!
S!C6D7!95!DEFAULT_CAPACITOR_1e+07pF_2_1!!CAP!!CAP_0603-22.0UF,4V,20%,X6S,E15431-004!!
S!C6D6!93!DEFAULT_CAPACITOR_1e+07pF_2_1!!CAP!!CAP_0603-22.0UF,4V,20%,X6S,E15431-004!!
S!C6D3!92!DEFAULT_CAPACITOR_1e+07pF_2_1!!CAP!!CAP_0603-22.0UF,4V,20%,X6S,E15431-004!!
S!C6D4!94!DEFAULT_CAPACITOR_1e+07pF_2_1!!CAP!!CAP_0603-22.0UF,4V,20%,X6S,E15431-004!!
S!C3D24!!DEFAULT_CAPACITOR_1e+07pF_2_1!!CAP!!CAP_0603-22.0UF,4V,20%,X6S,E15431-004!!
S!C3L24!!DEFAULT_CAPACITOR_2.2e+07pF_2_1!!CAP!!CAP_0603-22.0UF,4V,20%,X6S,E15431-004!!
S!C3L22!!DEFAULT_CAPACITOR_2.2e+07pF_2_1!!CAP!!CAP_0603-22.0UF,4V,20%,X6S,E15431-004!!
S!C3L23!!DEFAULT_CAPACITOR_2.2e+07pF_2_1!!CAP!!CAP_0603-22.0UF,4V,20%,X6S,E15431-004!!
S!C3M6!!DEFAULT_CAPACITOR_2.2e+07pF_2_1!!CAP!!CAP_0603-22.0UF,4V,20%,X6S,E15431-004!!
S!C3N11!!DEFAULT_CAPACITOR_2.2e+07pF_2_1!!CAP!!CAP_0603-22.0UF,4V,20%,X6S,E15431-004!!
S!C3N31!!DEFAULT_CAPACITOR_2.2e+07pF_2_1!!CAP!!CAP_0603-22.0UF,4V,20%,X6S,E15431-004!!
S!C3L27!!DEFAULT_CAPACITOR_2.2e+07pF_2_1!!CAP!!CAP_0603-22.0UF,4V,20%,X6S,E15431-004!!
S!C3N10!!DEFAULT_CAPACITOR_2.2e+07pF_2_1!!CAP!!CAP_0603-22.0UF,4V,20%,X6S,E15431-004!!
S!C3N28!!DEFAULT_CAPACITOR_2.2e+07pF_2_1!!CAP!!CAP_0603-22.0UF,4V,20%,X6S,E15431-004!!
S!C3L26!!DEFAULT_CAPACITOR_2.2e+07pF_2_1!!CAP!!CAP_0603-22.0UF,4V,20%,X6S,E15431-004!!
S!C3N12!!DEFAULT_CAPACITOR_2.2e+07pF_2_1!!CAP!!CAP_0603-22.0UF,4V,20%,X6S,E15431-004!!
S!C3N24!!DEFAULT_CAPACITOR_2.2e+07pF_2_1!!CAP!!CAP_0603-22.0UF,4V,20%,X6S,E15431-004!!
S!C3M7!!DEFAULT_CAPACITOR_2.2e+07pF_2_1!!CAP!!CAP_0603-22.0UF,4V,20%,X6S,E15431-004!!
S!C7A36!!DEFAULT_CAPACITOR_2.2e+07pF_2_1!!CAP!!CAP_0603-22.0UF,4V,20%,X6S,E15431-004!!
S!C3N30!!DEFAULT_CAPACITOR_2.2e+07pF_2_1!!CAP!!CAP_0603-22.0UF,4V,20%,X6S,E15431-004!!
S!C7C9!!DEFAULT_CAPACITOR_2.2e+07pF_2_1!!CAP!!CAP_0603-22.0UF,4V,20%,X6S,E15431-004!!
S!C3L25!!DEFAULT_CAPACITOR_2.2e+07pF_2_1!!CAP!!CAP_0603-22.0UF,4V,20%,X6S,E15431-004!!
S!C3N27!!DEFAULT_CAPACITOR_2.2e+07pF_2_1!!CAP!!CAP_0603-22.0UF,4V,20%,X6S,E15431-004!!
S!C2M2!!DEFAULT_CAPACITOR_2.2e+07pF_2_1!!CAP!!CAP_0603-22.0UF,4V,20%,X6S,E15431-004!!
S!C8B4!!DEFAULT_CAPACITOR_2.2e+07pF_2_1!!CAP!!CAP_0603-22.0UF,4V,20%,X6S,E15431-004!!
S!C7D3!!DEFAULT_CAPACITOR_2.2e+07pF_2_1!!CAP!!CAP_0603-22.0UF,4V,20%,X6S,E15431-004!!
S!C2M1!!DEFAULT_CAPACITOR_2.2e+07pF_2_1!!CAP!!CAP_0603-22.0UF,4V,20%,X6S,E15431-004!!
S!C8B2!!DEFAULT_CAPACITOR_2.2e+07pF_2_1!!CAP!!CAP_0603-22.0UF,4V,20%,X6S,E15431-004!!
S!C8B1!!DEFAULT_CAPACITOR_2.2e+07pF_2_1!!CAP!!CAP_0603-22.0UF,4V,20%,X6S,E15431-004!!
S!C7B17!!DEFAULT_CAPACITOR_2.2e+07pF_2_1!!CAP!!CAP_0603-22.0UF,4V,20%,X6S,E15431-004!!
S!C7B20!!DEFAULT_CAPACITOR_2.2e+07pF_2_1!!CAP!!CAP_0603-22.0UF,4V,20%,X6S,E15431-004!!
S!C7B18!!DEFAULT_CAPACITOR_2.2e+07pF_2_1!!CAP!!CAP_0603-22.0UF,4V,20%,X6S,E15431-004!!
S!C7B21!!DEFAULT_CAPACITOR_2.2e+07pF_2_1!!CAP!!CAP_0603-22.0UF,4V,20%,X6S,E15431-004!!
S!C7B24!!DEFAULT_CAPACITOR_2.2e+07pF_2_1!!CAP!!CAP_0603-22.0UF,4V,20%,X6S,E15431-004!!
S!C7B16!!DEFAULT_CAPACITOR_2.2e+07pF_2_1!!CAP!!CAP_0603-22.0UF,4V,20%,X6S,E15431-004!!
S!C7B22!!DEFAULT_CAPACITOR_2.2e+07pF_2_1!!CAP!!CAP_0603-22.0UF,4V,20%,X6S,E15431-004!!
S!C7B19!!DEFAULT_CAPACITOR_2.2e+07pF_2_1!!CAP!!CAP_0603-22.0UF,4V,20%,X6S,E15431-004!!
S!C7B23!!DEFAULT_CAPACITOR_2.2e+07pF_2_1!!CAP!!CAP_0603-22.0UF,4V,20%,X6S,E15431-004!!
S!C7B15!!DEFAULT_CAPACITOR_2.2e+07pF_2_1!!CAP!!CAP_0603-22.0UF,4V,20%,X6S,E15431-004!!
S!C8B13!!DEFAULT_CAPACITOR_2.2e+07pF_2_1!!CAP!!CAP_0603-22.0UF,4V,20%,X6S,E15431-004!!
S!C8B14!!DEFAULT_CAPACITOR_2.2e+07pF_2_1!!CAP!!CAP_0603-22.0UF,4V,20%,X6S,E15431-004!!
S!C8B11!!DEFAULT_CAPACITOR_2.2e+07pF_2_1!!CAP!!CAP_0603-22.0UF,4V,20%,X6S,E15431-004!!
S!C8B9!!DEFAULT_CAPACITOR_2.2e+07pF_2_1!!CAP!!CAP_0603-22.0UF,4V,20%,X6S,E15431-004!!
S!C8B10!!DEFAULT_CAPACITOR_2.2e+07pF_2_1!!CAP!!CAP_0603-22.0UF,4V,20%,X6S,E15431-004!!
S!C8B3!!DEFAULT_CAPACITOR_2.2e+07pF_2_1!!CAP!!CAP_0603-22.0UF,4V,20%,X6S,E15431-004!!
S!C2M12!!DEFAULT_CAPACITOR_2.2e+07pF_2_1!!CAP!!CAP_0603-22.0UF,4V,20%,X6S,E15431-004!!
S!C2N10!!DEFAULT_CAPACITOR_2.2e+07pF_2_1!!CAP!!CAP_0603-22.0UF,4V,20%,X6S,E15431-004!!
S!C2M13!!DEFAULT_CAPACITOR_2.2e+07pF_2_1!!CAP!!CAP_0603-22.0UF,4V,20%,X6S,E15431-004!!
S!R7P17!!DEFAULT_RESISTOR_90.900000OHM_2_1!!RES!!RES_0402-90.9,1%,1/16W,CHIP,G21796-365!!
S!R4P10!137!DEFAULT_RESISTOR_90.900000OHM_2_1!!RES!!RES_0402-90.9,1%,1/16W,CHIP,G21796-365!!
S!R4P8!143!DEFAULT_RESISTOR_90.900000OHM_2_1!!RES!!RES_0402-90.9,1%,1/16W,CHIP,G21796-365!!
S!R5D2!138!DEFAULT_RESISTOR_90.900000OHM_2_1!!RES!!RES_0402-90.9,1%,1/16W,CHIP,G21796-365!!
S!R5D1!144!DEFAULT_RESISTOR_90.900000OHM_2_1!!RES!!RES_0402-90.9,1%,1/16W,CHIP,G21796-365!!
S!R7P16!!DEFAULT_RESISTOR_90.900000OHM_2_1!!RES!!RES_0402-90.9,1%,1/16W,CHIP,G21796-365!!
S!R3D2!!DEFAULT_RESISTOR_90.900000OHM_2_1!!RES!!RES_0402-90.9,1%,1/16W,CHIP,G21796-365!!
S!R3D1!!DEFAULT_RESISTOR_90.900000OHM_2_1!!RES!!RES_0402-90.9,1%,1/16W,CHIP,G21796-365!!
S!R1U50!!DEFAULT_RESISTOR_200000OHM_2_1!!RES!!RES_0402-200.0K,1%,1/16W,CHIP,G21796-080!!
S!C9G8!!!!CAP!!CAP_0402-0.1UF,16V,10%,EMPTY,A36096-030!!
S!C9G10!!!!CAP!!CAP_0402-0.1UF,16V,10%,EMPTY,A36096-030!!
S!C9G11!!!!CAP!!CAP_0402-0.1UF,16V,10%,EMPTY,A36096-030!!
S!Q7E8!!!!FET_N!!FET_N_SOT23-2N7002,FET,C79254-001!!
S!Q2P2!!!!FET_N!!FET_N_SOT23-2N7002,FET,C79254-001!!
S!Q8D2!!!!FET_N!!FET_N_SOT23-2N7002,FET,C79254-001!!
S!Q7E4!!!!FET_N!!FET_N_SOT23-2N7002,FET,C79254-001!!
S!Q6F1!!!!FET_N!!FET_N_SOT23-2N7002,FET,C79254-001!!
S!Q7D1!!!!FET_N!!FET_N_SOT23-2N7002,FET,C79254-001!!
S!U8D4!!!!AT24C64!!AT24C64_SOICLF-IC,C47049-001!!
S!C1M4!5!!!CAP!!CAP_0402LF-47.0PF,50V,5%,EMPTY,A36095-025!!
S!C1E19!9!!!CAP!!CAP_0402LF-47.0PF,50V,5%,EMPTY,A36095-025!!
S!L2M1!!DEFAULT_INDUCTOR_22.000000nH_2_1!!INDUCTOR!!INDUCTOR_SMT-0.022UH,IND,721891-082!!
S!Q9B1!1!!!PNP!!PNP_TO92-MPS2907,IC,G73554-001!!
S!Q1E1!1!!!PNP!!PNP_TO92-MPS2907,IC,G73554-001!!
S!U9B4!10!!!TMP421!!TMP421_TSSOP-IC,G62962-001!!
S!U1E1!8!!!TMP421!!TMP421_TSSOP-IC,G62962-001!!
S!C9E11!!DEFAULT_CAPACITOR_100000pF_2_1!!CAP!!CAP_0402-1.0UF,16V,10%,X6S,D97712-011!!
S!C1D19!!!!CAP!!CAP_0402-1.0UF,16V,10%,X6S,D97712-011!!
S!C4E10!38!DEFAULT_CAPACITOR_1e+06pF_2_1!!CAP!!CAP_0402-1.0UF,16V,10%,X6S,D97712-011!!
S!C7C12!424!DEFAULT_CAPACITOR_1e+06pF_2_1!!CAP!!CAP_0402-1.0UF,16V,10%,X6S,D97712-011!!
S!C7C17!423!DEFAULT_CAPACITOR_1e+06pF_2_1!!CAP!!CAP_0402-1.0UF,16V,10%,X6S,D97712-011!!
S!C3T10!1!DEFAULT_CAPACITOR_1e+06pF_2_1!!CAP!!CAP_0402-1.0UF,16V,10%,X6S,D97712-011!!
S!C8E14!1!DEFAULT_CAPACITOR_1e+06pF_2_1!!CAP!!CAP_0402-1.0UF,16V,10%,X6S,D97712-011!!
S!C3M9!1!DEFAULT_CAPACITOR_1e+06pF_2_1!!CAP!!CAP_0402-1.0UF,16V,10%,X6S,D97712-011!!
S!C4G4!1!DEFAULT_CAPACITOR_1e+06pF_2_1!!CAP!!CAP_0402-1.0UF,16V,10%,X6S,D97712-011!!
S!C6L11!1!DEFAULT_CAPACITOR_1e+06pF_2_1!!CAP!!CAP_0402-1.0UF,16V,10%,X6S,D97712-011!!
S!C4C6!80!DEFAULT_CAPACITOR_1e+06pF_2_1!!CAP!!CAP_0402-1.0UF,16V,10%,X6S,D97712-011!!
S!C4D48!24!DEFAULT_CAPACITOR_1e+06pF_2_1!!CAP!!CAP_0402-1.0UF,16V,10%,X6S,D97712-011!!
S!C4E19!10!DEFAULT_CAPACITOR_1e+06pF_2_1!!CAP!!CAP_0402-1.0UF,16V,10%,X6S,D97712-011!!
S!C4E26!53!DEFAULT_CAPACITOR_1e+06pF_2_1!!CAP!!CAP_0402-1.0UF,16V,10%,X6S,D97712-011!!
S!C4D30!!DEFAULT_CAPACITOR_1e+06pF_2_1!!CAP!!CAP_0402-1.0UF,16V,10%,X6S,D97712-011!!
S!C4D10!!DEFAULT_CAPACITOR_1e+06pF_2_1!!CAP!!CAP_0402-1.0UF,16V,10%,X6S,D97712-011!!
S!C4D16!!DEFAULT_CAPACITOR_1e+06pF_2_1!!CAP!!CAP_0402-1.0UF,16V,10%,X6S,D97712-011!!
S!C4D7!!DEFAULT_CAPACITOR_1e+06pF_2_1!!CAP!!CAP_0402-1.0UF,16V,10%,X6S,D97712-011!!
S!C4D46!66!DEFAULT_CAPACITOR_1e+06pF_2_1!!CAP!!CAP_0402-1.0UF,16V,10%,X6S,D97712-011!!
S!C7G37!67!DEFAULT_CAPACITOR_1e+06pF_2_1!!CAP!!CAP_0402-1.0UF,16V,10%,X6S,D97712-011!!
S!C7G30!23!DEFAULT_CAPACITOR_1e+06pF_2_1!!CAP!!CAP_0402-1.0UF,16V,10%,X6S,D97712-011!!
S!C7G33!72!DEFAULT_CAPACITOR_1e+06pF_2_1!!CAP!!CAP_0402-1.0UF,16V,10%,X6S,D97712-011!!
S!C4C9!67!DEFAULT_CAPACITOR_1e+06pF_2_1!!CAP!!CAP_0402-1.0UF,16V,10%,X6S,D97712-011!!
S!C7G40!41!DEFAULT_CAPACITOR_1e+06pF_2_1!!CAP!!CAP_0402-1.0UF,16V,10%,X6S,D97712-011!!
S!C7A21!18!DEFAULT_CAPACITOR_1e+06pF_2_1!!CAP!!CAP_0402-1.0UF,16V,10%,X6S,D97712-011!!
S!C7A16!35!DEFAULT_CAPACITOR_1e+06pF_2_1!!CAP!!CAP_0402-1.0UF,16V,10%,X6S,D97712-011!!
S!C7A24!19!DEFAULT_CAPACITOR_1e+06pF_2_1!!CAP!!CAP_0402-1.0UF,16V,10%,X6S,D97712-011!!
S!C1A19!93!DEFAULT_CAPACITOR_1e+06pF_2_1!!CAP!!CAP_0402-1.0UF,16V,10%,X6S,D97712-011!!
S!C1A9!84!DEFAULT_CAPACITOR_1e+06pF_2_1!!CAP!!CAP_0402-1.0UF,16V,10%,X6S,D97712-011!!
S!C1B20!118!DEFAULT_CAPACITOR_1e+06pF_2_1!!CAP!!CAP_0402-1.0UF,16V,10%,X6S,D97712-011!!
S!C1F27!13!DEFAULT_CAPACITOR_1e+06pF_2_1!!CAP!!CAP_0402-1.0UF,16V,10%,X6S,D97712-011!!
S!C1G13!6!DEFAULT_CAPACITOR_1e+06pF_2_1!!CAP!!CAP_0402-1.0UF,16V,10%,X6S,D97712-011!!
S!C1G6!5!DEFAULT_CAPACITOR_1e+06pF_2_1!!CAP!!CAP_0402-1.0UF,16V,10%,X6S,D97712-011!!
S!C1G28!12!DEFAULT_CAPACITOR_1e+06pF_2_1!!CAP!!CAP_0402-1.0UF,16V,10%,X6S,D97712-011!!
S!C1E8!6!DEFAULT_CAPACITOR_1e+06pF_2_1!!CAP!!CAP_0402-1.0UF,16V,10%,X6S,D97712-011!!
S!C1E24!!DEFAULT_CAPACITOR_1e+06pF_2_1!!CAP!!CAP_0402-1.0UF,16V,10%,X6S,D97712-011!!
S!C1D35!!DEFAULT_CAPACITOR_1e+06pF_2_1!!CAP!!CAP_0402-1.0UF,16V,10%,X6S,D97712-011!!
S!C1E13!3!DEFAULT_CAPACITOR_1e+06pF_2_1!!CAP!!CAP_0402-1.0UF,16V,10%,X6S,D97712-011!!
S!C1D23!9!DEFAULT_CAPACITOR_1e+06pF_2_1!!CAP!!CAP_0402-1.0UF,16V,10%,X6S,D97712-011!!
S!C1D12!!DEFAULT_CAPACITOR_1e+06pF_2_1!!CAP!!CAP_0402-1.0UF,16V,10%,X6S,D97712-011!!
S!C1D17!8!DEFAULT_CAPACITOR_1e+06pF_2_1!!CAP!!CAP_0402-1.0UF,16V,10%,X6S,D97712-011!!
S!C1D7!!DEFAULT_CAPACITOR_1e+06pF_2_1!!CAP!!CAP_0402-1.0UF,16V,10%,X6S,D97712-011!!
S!C1C15!!DEFAULT_CAPACITOR_1e+06pF_2_1!!CAP!!CAP_0402-1.0UF,16V,10%,X6S,D97712-011!!
S!C1C5!!DEFAULT_CAPACITOR_1e+06pF_2_1!!CAP!!CAP_0402-1.0UF,16V,10%,X6S,D97712-011!!
S!C4C18!39!DEFAULT_CAPACITOR_1e+06pF_2_1!!CAP!!CAP_0402-1.0UF,16V,10%,X6S,D97712-011!!
S!C7E14!1!DEFAULT_CAPACITOR_1e+06pF_2_1!!CAP!!CAP_0402-1.0UF,16V,10%,X6S,D97712-011!!
S!C1A6!91!DEFAULT_CAPACITOR_1e+06pF_2_1!!CAP!!CAP_0402-1.0UF,16V,10%,X6S,D97712-011!!
S!C1C26!34!DEFAULT_CAPACITOR_1e+06pF_2_1!!CAP!!CAP_0402-1.0UF,16V,10%,X6S,D97712-011!!
S!C1D32!!DEFAULT_CAPACITOR_1e+06pF_2_1!!CAP!!CAP_0402-1.0UF,16V,10%,X6S,D97712-011!!
S!C7A11!25!DEFAULT_CAPACITOR_1e+06pF_2_1!!CAP!!CAP_0402-1.0UF,16V,10%,X6S,D97712-011!!
S!C4E15!333!DEFAULT_CAPACITOR_1e+06pF_2_1!!CAP!!CAP_0402-1.0UF,16V,10%,X6S,D97712-011!!
S!C4E22!330!DEFAULT_CAPACITOR_1e+06pF_2_1!!CAP!!CAP_0402-1.0UF,16V,10%,X6S,D97712-011!!
S!C7A9!14!DEFAULT_CAPACITOR_1e+06pF_2_1!!CAP!!CAP_0402-1.0UF,16V,10%,X6S,D97712-011!!
S!C7A7!!DEFAULT_CAPACITOR_1e+06pF_2_1!!CAP!!CAP_0402-1.0UF,16V,10%,X6S,D97712-011!!
S!C7A6!!DEFAULT_CAPACITOR_1e+06pF_2_1!!CAP!!CAP_0402-1.0UF,16V,10%,X6S,D97712-011!!
S!C7A10!13!DEFAULT_CAPACITOR_1e+06pF_2_1!!CAP!!CAP_0402-1.0UF,16V,10%,X6S,D97712-011!!
S!C1D25!14!DEFAULT_CAPACITOR_1e+06pF_2_1!!CAP!!CAP_0402-1.0UF,16V,10%,X6S,D97712-011!!
S!C1L19!!DEFAULT_CAPACITOR_1e+06pF_2_1!!CAP!!CAP_0402-1.0UF,16V,10%,X6S,D97712-011!!
S!C1L1!!DEFAULT_CAPACITOR_1e+06pF_2_1!!CAP!!CAP_0402-1.0UF,16V,10%,X6S,D97712-011!!
S!C7D4!13!DEFAULT_CAPACITOR_1e+06pF_2_1!!CAP!!CAP_0402-1.0UF,16V,10%,X6S,D97712-011!!
S!C3P50!26!DEFAULT_CAPACITOR_1e+06pF_2_1!!CAP!!CAP_0402-1.0UF,16V,10%,X6S,D97712-011!!
S!C1U19!!DEFAULT_CAPACITOR_1e+06pF_2_1!!CAP!!CAP_0402-1.0UF,16V,10%,X6S,D97712-011!!
S!C4G15!10!DEFAULT_CAPACITOR_1e+06pF_2_1!!CAP!!CAP_0402-1.0UF,16V,10%,X6S,D97712-011!!
S!C4G16!!DEFAULT_CAPACITOR_1e+06pF_2_1!!CAP!!CAP_0402-1.0UF,16V,10%,X6S,D97712-011!!
S!C4A9!!DEFAULT_CAPACITOR_1e+06pF_2_1!!CAP!!CAP_0402-1.0UF,16V,10%,X6S,D97712-011!!
S!C4G21!!DEFAULT_CAPACITOR_1e+06pF_2_1!!CAP!!CAP_0402-1.0UF,16V,10%,X6S,D97712-011!!
S!C4A14!!DEFAULT_CAPACITOR_1e+06pF_2_1!!CAP!!CAP_0402-1.0UF,16V,10%,X6S,D97712-011!!
S!C4A10!!DEFAULT_CAPACITOR_1e+06pF_2_1!!CAP!!CAP_0402-1.0UF,16V,10%,X6S,D97712-011!!
S!C4G18!!DEFAULT_CAPACITOR_1e+06pF_2_1!!CAP!!CAP_0402-1.0UF,16V,10%,X6S,D97712-011!!
S!C4A8!!DEFAULT_CAPACITOR_1e+06pF_2_1!!CAP!!CAP_0402-1.0UF,16V,10%,X6S,D97712-011!!
S!EU4G3!5!!!MIC5166!!MIC5166_DFN-IC,H55101-001!!
S!EU4A1!!!!MIC5166!!MIC5166_DFN-IC,H55101-001!!
S!EU4G2!!!!MIC5166!!MIC5166_DFN-IC,H55101-001!!
S!EU4A2!!!!MIC5166!!MIC5166_DFN-IC,H55101-001!!
S!U4F1!111!!!MAX9634!!MAX9634_SOT-IC,H35789-001!!
S!U4B1!!!!MAX9634!!MAX9634_SOT-IC,H35789-001!!
S!U1F1!!!!MAX9634!!MAX9634_SOT-IC,H35789-001!!
S!U1B1!!!!MAX9634!!MAX9634_SOT-IC,H35789-001!!
S!R4F2!110!DEFAULT_RESISTOR_0.002OHM_2_1!!RES!!RES_1206-0.002,1%,1W,CHIP,G52199-004!!
S!R4B12!!DEFAULT_RESISTOR_0.002OHM_2_1!!RES!!RES_1206-0.002,1%,1W,CHIP,G52199-004!!
S!R1F3!!DEFAULT_RESISTOR_0.002OHM_2_1!!RES!!RES_1206-0.002,1%,1W,CHIP,G52199-004!!
S!R9M4!!DEFAULT_RESISTOR_0.002OHM_2_1!!RES!!RES_1206-0.002,1%,1W,CHIP,G52199-004!!
S!C2U3!!CAP_0402LF-0.220UF_6.3V_10%_EMA_NA!!CAP!!CAP_0402-0.22UF,16V,10%,X7R,A36096-155!!
S!C2U4!!CAP_0402LF-0.220UF_6.3V_10%_EMA_NA!!CAP!!CAP_0402-0.22UF,16V,10%,X7R,A36096-155!!
S!C2U5!!CAP_0402LF-0.220UF_6.3V_10%_EMA_NA!!CAP!!CAP_0402-0.22UF,16V,10%,X7R,A36096-155!!
S!C2U6!!CAP_0402LF-0.220UF_6.3V_10%_EMA_NA!!CAP!!CAP_0402-0.22UF,16V,10%,X7R,A36096-155!!
S!C2U7!!CAP_0402LF-0.220UF_6.3V_10%_EMA_NA!!CAP!!CAP_0402-0.22UF,16V,10%,X7R,A36096-155!!
S!C2U8!!CAP_0402LF-0.220UF_6.3V_10%_EMA_NA!!CAP!!CAP_0402-0.22UF,16V,10%,X7R,A36096-155!!
S!C2U9!!CAP_0402LF-0.220UF_6.3V_10%_EMA_NA!!CAP!!CAP_0402-0.22UF,16V,10%,X7R,A36096-155!!
S!C2U10!!CAP_0402LF-0.220UF_6.3V_10%_EMA_NA!!CAP!!CAP_0402-0.22UF,16V,10%,X7R,A36096-155!!
S!C2U11!!CAP_0402LF-0.220UF_6.3V_10%_EMA_NA!!CAP!!CAP_0402-0.22UF,16V,10%,X7R,A36096-155!!
S!C2U12!!CAP_0402LF-0.220UF_6.3V_10%_EMA_NA!!CAP!!CAP_0402-0.22UF,16V,10%,X7R,A36096-155!!
S!C2U13!!CAP_0402LF-0.220UF_6.3V_10%_EMA_NA!!CAP!!CAP_0402-0.22UF,16V,10%,X7R,A36096-155!!
S!C2U14!!CAP_0402LF-0.220UF_6.3V_10%_EMA_NA!!CAP!!CAP_0402-0.22UF,16V,10%,X7R,A36096-155!!
S!C2U15!!CAP_0402LF-0.220UF_6.3V_10%_EMA_NA!!CAP!!CAP_0402-0.22UF,16V,10%,X7R,A36096-155!!
S!C2U16!!CAP_0402LF-0.220UF_6.3V_10%_EMA_NA!!CAP!!CAP_0402-0.22UF,16V,10%,X7R,A36096-155!!
S!C2U17!!CAP_0402LF-0.220UF_6.3V_10%_EMA_NA!!CAP!!CAP_0402-0.22UF,16V,10%,X7R,A36096-155!!
S!C2U18!!CAP_0402LF-0.220UF_6.3V_10%_EMA_NA!!CAP!!CAP_0402-0.22UF,16V,10%,X7R,A36096-155!!
S!C3P11!!CAP_0402LF-0.220UF_6.3V_10%_EMA_NA!!CAP!!CAP_0402-0.22UF,16V,10%,X7R,A36096-155!!
S!C3P13!!CAP_0402LF-0.220UF_6.3V_10%_EMA_NA!!CAP!!CAP_0402-0.22UF,16V,10%,X7R,A36096-155!!
S!C3P15!!CAP_0402LF-0.220UF_6.3V_10%_EMA_NA!!CAP!!CAP_0402-0.22UF,16V,10%,X7R,A36096-155!!
S!C3P17!!CAP_0402LF-0.220UF_6.3V_10%_EMA_NA!!CAP!!CAP_0402-0.22UF,16V,10%,X7R,A36096-155!!
S!C3P18!!CAP_0402LF-0.220UF_6.3V_10%_EMA_NA!!CAP!!CAP_0402-0.22UF,16V,10%,X7R,A36096-155!!
S!C3P20!!CAP_0402LF-0.220UF_6.3V_10%_EMA_NA!!CAP!!CAP_0402-0.22UF,16V,10%,X7R,A36096-155!!
S!C3P23!!CAP_0402LF-0.220UF_6.3V_10%_EMA_NA!!CAP!!CAP_0402-0.22UF,16V,10%,X7R,A36096-155!!
S!C3P25!!CAP_0402LF-0.220UF_6.3V_10%_EMA_NA!!CAP!!CAP_0402-0.22UF,16V,10%,X7R,A36096-155!!
S!C3P27!!CAP_0402LF-0.220UF_6.3V_10%_EMA_NA!!CAP!!CAP_0402-0.22UF,16V,10%,X7R,A36096-155!!
S!C3P28!!CAP_0402LF-0.220UF_6.3V_10%_EMA_NA!!CAP!!CAP_0402-0.22UF,16V,10%,X7R,A36096-155!!
S!C3P30!!CAP_0402LF-0.220UF_6.3V_10%_EMA_NA!!CAP!!CAP_0402-0.22UF,16V,10%,X7R,A36096-155!!
S!C3P32!!CAP_0402LF-0.220UF_6.3V_10%_EMA_NA!!CAP!!CAP_0402-0.22UF,16V,10%,X7R,A36096-155!!
S!C3P35!!CAP_0402LF-0.220UF_6.3V_10%_EMA_NA!!CAP!!CAP_0402-0.22UF,16V,10%,X7R,A36096-155!!
S!C3P37!!CAP_0402LF-0.220UF_6.3V_10%_EMA_NA!!CAP!!CAP_0402-0.22UF,16V,10%,X7R,A36096-155!!
S!C3P39!!CAP_0402LF-0.220UF_6.3V_10%_EMA_NA!!CAP!!CAP_0402-0.22UF,16V,10%,X7R,A36096-155!!
S!C3P40!!CAP_0402LF-0.220UF_6.3V_10%_EMA_NA!!CAP!!CAP_0402-0.22UF,16V,10%,X7R,A36096-155!!
S!C8F7!!DEFAULT_CAPACITOR_10000pF_2_1!!CAP!!CAP_0402-0.22UF,16V,10%,X7R,A36096-155!!
S!C8F12!!DEFAULT_CAPACITOR_10000pF_2_1!!CAP!!CAP_0402-0.22UF,16V,10%,X7R,A36096-155!!
S!C3M2!!DEFAULT_CAPACITOR_220000pF_2_1!!CAP!!CAP_0402-0.22UF,16V,10%,X7R,A36096-155!!
S!C3M1!!DEFAULT_CAPACITOR_220000pF_2_1!!CAP!!CAP_0402-0.22UF,16V,10%,X7R,A36096-155!!
S!C3M11!!DEFAULT_CAPACITOR_220000pF_2_1!!CAP!!CAP_0402-0.22UF,16V,10%,X7R,A36096-155!!
S!C3M12!!DEFAULT_CAPACITOR_220000pF_2_1!!CAP!!CAP_0402-0.22UF,16V,10%,X7R,A36096-155!!
S!C3M13!!DEFAULT_CAPACITOR_220000pF_2_1!!CAP!!CAP_0402-0.22UF,16V,10%,X7R,A36096-155!!
S!C3M14!!DEFAULT_CAPACITOR_220000pF_2_1!!CAP!!CAP_0402-0.22UF,16V,10%,X7R,A36096-155!!
S!C3M3!!DEFAULT_CAPACITOR_220000pF_2_1!!CAP!!CAP_0402-0.22UF,16V,10%,X7R,A36096-155!!
S!C3M4!!DEFAULT_CAPACITOR_220000pF_2_1!!CAP!!CAP_0402-0.22UF,16V,10%,X7R,A36096-155!!
S!C3M25!!DEFAULT_CAPACITOR_220000pF_2_1!!CAP!!CAP_0402-0.22UF,16V,10%,X7R,A36096-155!!
S!C3M26!!DEFAULT_CAPACITOR_220000pF_2_1!!CAP!!CAP_0402-0.22UF,16V,10%,X7R,A36096-155!!
S!C3M28!!DEFAULT_CAPACITOR_220000pF_2_1!!CAP!!CAP_0402-0.22UF,16V,10%,X7R,A36096-155!!
S!C3M32!!DEFAULT_CAPACITOR_220000pF_2_1!!CAP!!CAP_0402-0.22UF,16V,10%,X7R,A36096-155!!
S!C3M36!!DEFAULT_CAPACITOR_220000pF_2_1!!CAP!!CAP_0402-0.22UF,16V,10%,X7R,A36096-155!!
S!C3M35!!DEFAULT_CAPACITOR_220000pF_2_1!!CAP!!CAP_0402-0.22UF,16V,10%,X7R,A36096-155!!
S!C3M34!!DEFAULT_CAPACITOR_220000pF_2_1!!CAP!!CAP_0402-0.22UF,16V,10%,X7R,A36096-155!!
S!C3M33!!DEFAULT_CAPACITOR_220000pF_2_1!!CAP!!CAP_0402-0.22UF,16V,10%,X7R,A36096-155!!
S!C6B4!!DEFAULT_CAPACITOR_220000pF_2_1!!CAP!!CAP_0402-0.22UF,16V,10%,X7R,A36096-155!!
S!C6B5!!DEFAULT_CAPACITOR_220000pF_2_1!!CAP!!CAP_0402-0.22UF,16V,10%,X7R,A36096-155!!
S!C6B6!!DEFAULT_CAPACITOR_220000pF_2_1!!CAP!!CAP_0402-0.22UF,16V,10%,X7R,A36096-155!!
S!C6B8!!DEFAULT_CAPACITOR_220000pF_2_1!!CAP!!CAP_0402-0.22UF,16V,10%,X7R,A36096-155!!
S!C6B9!!DEFAULT_CAPACITOR_220000pF_2_1!!CAP!!CAP_0402-0.22UF,16V,10%,X7R,A36096-155!!
S!C6B10!!DEFAULT_CAPACITOR_220000pF_2_1!!CAP!!CAP_0402-0.22UF,16V,10%,X7R,A36096-155!!
S!C6B11!!DEFAULT_CAPACITOR_220000pF_2_1!!CAP!!CAP_0402-0.22UF,16V,10%,X7R,A36096-155!!
S!C6B12!!DEFAULT_CAPACITOR_220000pF_2_1!!CAP!!CAP_0402-0.22UF,16V,10%,X7R,A36096-155!!
S!C6B14!!DEFAULT_CAPACITOR_220000pF_2_1!!CAP!!CAP_0402-0.22UF,16V,10%,X7R,A36096-155!!
S!C6B13!!DEFAULT_CAPACITOR_220000pF_2_1!!CAP!!CAP_0402-0.22UF,16V,10%,X7R,A36096-155!!
S!C6B15!!DEFAULT_CAPACITOR_220000pF_2_1!!CAP!!CAP_0402-0.22UF,16V,10%,X7R,A36096-155!!
S!C6B16!!DEFAULT_CAPACITOR_220000pF_2_1!!CAP!!CAP_0402-0.22UF,16V,10%,X7R,A36096-155!!
S!C6B17!!DEFAULT_CAPACITOR_220000pF_2_1!!CAP!!CAP_0402-0.22UF,16V,10%,X7R,A36096-155!!
S!C6B18!!DEFAULT_CAPACITOR_220000pF_2_1!!CAP!!CAP_0402-0.22UF,16V,10%,X7R,A36096-155!!
S!C6B19!!DEFAULT_CAPACITOR_220000pF_2_1!!CAP!!CAP_0402-0.22UF,16V,10%,X7R,A36096-155!!
S!C6B20!!DEFAULT_CAPACITOR_220000pF_2_1!!CAP!!CAP_0402-0.22UF,16V,10%,X7R,A36096-155!!
S!C1R8!!DEFAULT_CAPACITOR_220000pF_2_1!!CAP!!CAP_0402-0.22UF,16V,10%,X7R,A36096-155!!
S!C1R7!!DEFAULT_CAPACITOR_220000pF_2_1!!CAP!!CAP_0402-0.22UF,16V,10%,X7R,A36096-155!!
S!C1R6!!DEFAULT_CAPACITOR_220000pF_2_1!!CAP!!CAP_0402-0.22UF,16V,10%,X7R,A36096-155!!
S!C1R5!!DEFAULT_CAPACITOR_220000pF_2_1!!CAP!!CAP_0402-0.22UF,16V,10%,X7R,A36096-155!!
S!C1R4!!DEFAULT_CAPACITOR_220000pF_2_1!!CAP!!CAP_0402-0.22UF,16V,10%,X7R,A36096-155!!
S!C1R3!!DEFAULT_CAPACITOR_220000pF_2_1!!CAP!!CAP_0402-0.22UF,16V,10%,X7R,A36096-155!!
S!C2R10!!DEFAULT_CAPACITOR_220000pF_2_1!!CAP!!CAP_0402-0.22UF,16V,10%,X7R,A36096-155!!
S!C2R9!!DEFAULT_CAPACITOR_220000pF_2_1!!CAP!!CAP_0402-0.22UF,16V,10%,X7R,A36096-155!!
S!C2R8!!DEFAULT_CAPACITOR_220000pF_2_1!!CAP!!CAP_0402-0.22UF,16V,10%,X7R,A36096-155!!
S!C2R7!!DEFAULT_CAPACITOR_220000pF_2_1!!CAP!!CAP_0402-0.22UF,16V,10%,X7R,A36096-155!!
S!C2R14!!DEFAULT_CAPACITOR_220000pF_2_1!!CAP!!CAP_0402-0.22UF,16V,10%,X7R,A36096-155!!
S!C1R2!!DEFAULT_CAPACITOR_220000pF_2_1!!CAP!!CAP_0402-0.22UF,16V,10%,X7R,A36096-155!!
S!C1R1!!DEFAULT_CAPACITOR_220000pF_2_1!!CAP!!CAP_0402-0.22UF,16V,10%,X7R,A36096-155!!
S!C2R13!!DEFAULT_CAPACITOR_220000pF_2_1!!CAP!!CAP_0402-0.22UF,16V,10%,X7R,A36096-155!!
S!C1R10!!DEFAULT_CAPACITOR_220000pF_2_1!!CAP!!CAP_0402-0.22UF,16V,10%,X7R,A36096-155!!
S!C1R9!!DEFAULT_CAPACITOR_220000pF_2_1!!CAP!!CAP_0402-0.22UF,16V,10%,X7R,A36096-155!!
S!C1M6!!DEFAULT_CAPACITOR_220000pF_2_1!!CAP!!CAP_0402-0.22UF,16V,10%,X7R,A36096-155!!
S!C1M7!!DEFAULT_CAPACITOR_220000pF_2_1!!CAP!!CAP_0402-0.22UF,16V,10%,X7R,A36096-155!!
S!C1M8!!DEFAULT_CAPACITOR_220000pF_2_1!!CAP!!CAP_0402-0.22UF,16V,10%,X7R,A36096-155!!
S!C1M9!!DEFAULT_CAPACITOR_220000pF_2_1!!CAP!!CAP_0402-0.22UF,16V,10%,X7R,A36096-155!!
S!C1M10!!DEFAULT_CAPACITOR_220000pF_2_1!!CAP!!CAP_0402-0.22UF,16V,10%,X7R,A36096-155!!
S!C1M11!!DEFAULT_CAPACITOR_220000pF_2_1!!CAP!!CAP_0402-0.22UF,16V,10%,X7R,A36096-155!!
S!C1M12!!DEFAULT_CAPACITOR_220000pF_2_1!!CAP!!CAP_0402-0.22UF,16V,10%,X7R,A36096-155!!
S!C1M13!!DEFAULT_CAPACITOR_220000pF_2_1!!CAP!!CAP_0402-0.22UF,16V,10%,X7R,A36096-155!!
S!C1M14!!DEFAULT_CAPACITOR_220000pF_2_1!!CAP!!CAP_0402-0.22UF,16V,10%,X7R,A36096-155!!
S!C1M15!!DEFAULT_CAPACITOR_220000pF_2_1!!CAP!!CAP_0402-0.22UF,16V,10%,X7R,A36096-155!!
S!C1M16!!DEFAULT_CAPACITOR_220000pF_2_1!!CAP!!CAP_0402-0.22UF,16V,10%,X7R,A36096-155!!
S!C1M17!!DEFAULT_CAPACITOR_220000pF_2_1!!CAP!!CAP_0402-0.22UF,16V,10%,X7R,A36096-155!!
S!C1M18!!DEFAULT_CAPACITOR_220000pF_2_1!!CAP!!CAP_0402-0.22UF,16V,10%,X7R,A36096-155!!
S!C1M19!!DEFAULT_CAPACITOR_220000pF_2_1!!CAP!!CAP_0402-0.22UF,16V,10%,X7R,A36096-155!!
S!C2M14!!DEFAULT_CAPACITOR_220000pF_2_1!!CAP!!CAP_0402-0.22UF,16V,10%,X7R,A36096-155!!
S!C2M15!!DEFAULT_CAPACITOR_220000pF_2_1!!CAP!!CAP_0402-0.22UF,16V,10%,X7R,A36096-155!!
S!C7G21!!DEFAULT_CAPACITOR_220000pF_2_1!!CAP!!CAP_0402-0.22UF,16V,10%,X7R,A36096-155!!
S!C7G22!!DEFAULT_CAPACITOR_220000pF_2_1!!CAP!!CAP_0402-0.22UF,16V,10%,X7R,A36096-155!!
S!C7G23!!DEFAULT_CAPACITOR_220000pF_2_1!!CAP!!CAP_0402-0.22UF,16V,10%,X7R,A36096-155!!
S!C7G24!!DEFAULT_CAPACITOR_220000pF_2_1!!CAP!!CAP_0402-0.22UF,16V,10%,X7R,A36096-155!!
S!C7G25!!DEFAULT_CAPACITOR_220000pF_2_1!!CAP!!CAP_0402-0.22UF,16V,10%,X7R,A36096-155!!
S!C7G26!!DEFAULT_CAPACITOR_220000pF_2_1!!CAP!!CAP_0402-0.22UF,16V,10%,X7R,A36096-155!!
S!C8G1!!DEFAULT_CAPACITOR_220000pF_2_1!!CAP!!CAP_0402-0.22UF,16V,10%,X7R,A36096-155!!
S!C8G2!!DEFAULT_CAPACITOR_220000pF_2_1!!CAP!!CAP_0402-0.22UF,16V,10%,X7R,A36096-155!!
S!C8G3!!DEFAULT_CAPACITOR_220000pF_2_1!!CAP!!CAP_0402-0.22UF,16V,10%,X7R,A36096-155!!
S!C8G4!!DEFAULT_CAPACITOR_220000pF_2_1!!CAP!!CAP_0402-0.22UF,16V,10%,X7R,A36096-155!!
S!C8G5!!DEFAULT_CAPACITOR_220000pF_2_1!!CAP!!CAP_0402-0.22UF,16V,10%,X7R,A36096-155!!
S!C8G6!!DEFAULT_CAPACITOR_220000pF_2_1!!CAP!!CAP_0402-0.22UF,16V,10%,X7R,A36096-155!!
S!C8G8!!DEFAULT_CAPACITOR_220000pF_2_1!!CAP!!CAP_0402-0.22UF,16V,10%,X7R,A36096-155!!
S!C8G7!!DEFAULT_CAPACITOR_220000pF_2_1!!CAP!!CAP_0402-0.22UF,16V,10%,X7R,A36096-155!!
S!C8G9!!DEFAULT_CAPACITOR_220000pF_2_1!!CAP!!CAP_0402-0.22UF,16V,10%,X7R,A36096-155!!
S!C8G10!!DEFAULT_CAPACITOR_220000pF_2_1!!CAP!!CAP_0402-0.22UF,16V,10%,X7R,A36096-155!!
S!C7G5!!DEFAULT_CAPACITOR_220000pF_2_1!!CAP!!CAP_0402-0.22UF,16V,10%,X7R,A36096-155!!
S!C7G7!!DEFAULT_CAPACITOR_220000pF_2_1!!CAP!!CAP_0402-0.22UF,16V,10%,X7R,A36096-155!!
S!C7G9!!DEFAULT_CAPACITOR_220000pF_2_1!!CAP!!CAP_0402-0.22UF,16V,10%,X7R,A36096-155!!
S!C7G10!!DEFAULT_CAPACITOR_220000pF_2_1!!CAP!!CAP_0402-0.22UF,16V,10%,X7R,A36096-155!!
S!C7G11!!DEFAULT_CAPACITOR_220000pF_2_1!!CAP!!CAP_0402-0.22UF,16V,10%,X7R,A36096-155!!
S!C7G12!!DEFAULT_CAPACITOR_220000pF_2_1!!CAP!!CAP_0402-0.22UF,16V,10%,X7R,A36096-155!!
S!C7G14!!DEFAULT_CAPACITOR_220000pF_2_1!!CAP!!CAP_0402-0.22UF,16V,10%,X7R,A36096-155!!
S!C7G13!!DEFAULT_CAPACITOR_220000pF_2_1!!CAP!!CAP_0402-0.22UF,16V,10%,X7R,A36096-155!!
S!C7G15!!DEFAULT_CAPACITOR_220000pF_2_1!!CAP!!CAP_0402-0.22UF,16V,10%,X7R,A36096-155!!
S!C7G16!!DEFAULT_CAPACITOR_220000pF_2_1!!CAP!!CAP_0402-0.22UF,16V,10%,X7R,A36096-155!!
S!C7G17!!DEFAULT_CAPACITOR_220000pF_2_1!!CAP!!CAP_0402-0.22UF,16V,10%,X7R,A36096-155!!
S!C7G18!!DEFAULT_CAPACITOR_220000pF_2_1!!CAP!!CAP_0402-0.22UF,16V,10%,X7R,A36096-155!!
S!C7G19!!DEFAULT_CAPACITOR_220000pF_2_1!!CAP!!CAP_0402-0.22UF,16V,10%,X7R,A36096-155!!
S!C7G20!!DEFAULT_CAPACITOR_220000pF_2_1!!CAP!!CAP_0402-0.22UF,16V,10%,X7R,A36096-155!!
S!C7G6!!DEFAULT_CAPACITOR_220000pF_2_1!!CAP!!CAP_0402-0.22UF,16V,10%,X7R,A36096-155!!
S!C7G8!!DEFAULT_CAPACITOR_220000pF_2_1!!CAP!!CAP_0402-0.22UF,16V,10%,X7R,A36096-155!!
S!C9N17!!DEFAULT_CAPACITOR_220000pF_2_1!!CAP!!CAP_0402-0.22UF,16V,10%,X7R,A36096-155!!
S!C9N12!!DEFAULT_CAPACITOR_220000pF_2_1!!CAP!!CAP_0402-0.22UF,16V,10%,X7R,A36096-155!!
S!C9N2!!DEFAULT_CAPACITOR_220000pF_2_1!!CAP!!CAP_0402-0.22UF,16V,10%,X7R,A36096-155!!
S!C9N10!!DEFAULT_CAPACITOR_220000pF_2_1!!CAP!!CAP_0402-0.22UF,16V,10%,X7R,A36096-155!!
S!C9N7!!DEFAULT_CAPACITOR_220000pF_2_1!!CAP!!CAP_0402-0.22UF,16V,10%,X7R,A36096-155!!
S!C9N4!!DEFAULT_CAPACITOR_220000pF_2_1!!CAP!!CAP_0402-0.22UF,16V,10%,X7R,A36096-155!!
S!C9N14!!DEFAULT_CAPACITOR_220000pF_2_1!!CAP!!CAP_0402-0.22UF,16V,10%,X7R,A36096-155!!
S!C9N5!!DEFAULT_CAPACITOR_220000pF_2_1!!CAP!!CAP_0402-0.22UF,16V,10%,X7R,A36096-155!!
S!C9N8!!DEFAULT_CAPACITOR_220000pF_2_1!!CAP!!CAP_0402-0.22UF,16V,10%,X7R,A36096-155!!
S!C9N9!!DEFAULT_CAPACITOR_220000pF_2_1!!CAP!!CAP_0402-0.22UF,16V,10%,X7R,A36096-155!!
S!C9N3!!DEFAULT_CAPACITOR_220000pF_2_1!!CAP!!CAP_0402-0.22UF,16V,10%,X7R,A36096-155!!
S!C9N16!!DEFAULT_CAPACITOR_220000pF_2_1!!CAP!!CAP_0402-0.22UF,16V,10%,X7R,A36096-155!!
S!C9N6!!DEFAULT_CAPACITOR_220000pF_2_1!!CAP!!CAP_0402-0.22UF,16V,10%,X7R,A36096-155!!
S!C9N18!!DEFAULT_CAPACITOR_220000pF_2_1!!CAP!!CAP_0402-0.22UF,16V,10%,X7R,A36096-155!!
S!C9N15!!DEFAULT_CAPACITOR_220000pF_2_1!!CAP!!CAP_0402-0.22UF,16V,10%,X7R,A36096-155!!
S!C9N1!!DEFAULT_CAPACITOR_220000pF_2_1!!CAP!!CAP_0402-0.22UF,16V,10%,X7R,A36096-155!!
S!C7A41!10!DEFAULT_CAPACITOR_220000pF_2_1!!CAP!!CAP_0402-0.22UF,16V,10%,X7R,A36096-155!!
S!C7A8!!DEFAULT_CAPACITOR_220000pF_2_1!!CAP!!CAP_0402-0.22UF,16V,10%,X7R,A36096-155!!
S!C4E23!327!DEFAULT_CAPACITOR_220000pF_2_1!!CAP!!CAP_0402-0.22UF,16V,10%,X7R,A36096-155!!
S!C4D5!!DEFAULT_CAPACITOR_220000pF_2_1!!CAP!!CAP_0402-0.22UF,16V,10%,X7R,A36096-155!!
S!C4D13!!DEFAULT_CAPACITOR_220000pF_2_1!!CAP!!CAP_0402-0.22UF,16V,10%,X7R,A36096-155!!
S!C2T20!!DEFAULT_CAPACITOR_220000pF_2_1!!CAP!!CAP_0402-0.22UF,16V,10%,X7R,A36096-155!!
S!C2T23!!DEFAULT_CAPACITOR_220000pF_2_1!!CAP!!CAP_0402-0.22UF,16V,10%,X7R,A36096-155!!
S!C2T13!!DEFAULT_CAPACITOR_220000pF_2_1!!CAP!!CAP_0402-0.22UF,16V,10%,X7R,A36096-155!!
S!C2T14!!DEFAULT_CAPACITOR_220000pF_2_1!!CAP!!CAP_0402-0.22UF,16V,10%,X7R,A36096-155!!
S!C2T10!!DEFAULT_CAPACITOR_220000pF_2_1!!CAP!!CAP_0402-0.22UF,16V,10%,X7R,A36096-155!!
S!C2T11!!DEFAULT_CAPACITOR_220000pF_2_1!!CAP!!CAP_0402-0.22UF,16V,10%,X7R,A36096-155!!
S!C7B25!!DEFAULT_CAPACITOR_220000pF_2_1!!CAP!!CAP_0402-0.22UF,16V,10%,X7R,A36096-155!!
S!C7B28!!DEFAULT_CAPACITOR_220000pF_2_1!!CAP!!CAP_0402-0.22UF,16V,10%,X7R,A36096-155!!
S!C3N8!!DEFAULT_CAPACITOR_220000pF_2_1!!CAP!!CAP_0402-0.22UF,16V,10%,X7R,A36096-155!!
S!C3M37!!DEFAULT_CAPACITOR_220000pF_2_1!!CAP!!CAP_0402-0.22UF,16V,10%,X7R,A36096-155!!
S!C7B27!!DEFAULT_CAPACITOR_220000pF_2_1!!CAP!!CAP_0402-0.22UF,16V,10%,X7R,A36096-155!!
S!C7C2!!DEFAULT_CAPACITOR_220000pF_2_1!!CAP!!CAP_0402-0.22UF,16V,10%,X7R,A36096-155!!
S!C3N9!!DEFAULT_CAPACITOR_220000pF_2_1!!CAP!!CAP_0402-0.22UF,16V,10%,X7R,A36096-155!!
S!C3M40!!DEFAULT_CAPACITOR_220000pF_2_1!!CAP!!CAP_0402-0.22UF,16V,10%,X7R,A36096-155!!
S!C7B26!!DEFAULT_CAPACITOR_220000pF_2_1!!CAP!!CAP_0402-0.22UF,16V,10%,X7R,A36096-155!!
S!C7C1!!DEFAULT_CAPACITOR_220000pF_2_1!!CAP!!CAP_0402-0.22UF,16V,10%,X7R,A36096-155!!
S!C3N13!!DEFAULT_CAPACITOR_220000pF_2_1!!CAP!!CAP_0402-0.22UF,16V,10%,X7R,A36096-155!!
S!C3M41!!DEFAULT_CAPACITOR_220000pF_2_1!!CAP!!CAP_0402-0.22UF,16V,10%,X7R,A36096-155!!
S!C7B29!!DEFAULT_CAPACITOR_220000pF_2_1!!CAP!!CAP_0402-0.22UF,16V,10%,X7R,A36096-155!!
S!C7C3!!DEFAULT_CAPACITOR_220000pF_2_1!!CAP!!CAP_0402-0.22UF,16V,10%,X7R,A36096-155!!
S!C3M45!!DEFAULT_CAPACITOR_220000pF_2_1!!CAP!!CAP_0402-0.22UF,16V,10%,X7R,A36096-155!!
S!C3M44!!DEFAULT_CAPACITOR_220000pF_2_1!!CAP!!CAP_0402-0.22UF,16V,10%,X7R,A36096-155!!
S!C4E27!56!DEFAULT_CAPACITOR_220000pF_2_1!!CAP!!CAP_0402-0.22UF,16V,10%,X7R,A36096-155!!
S!C4E5!42!DEFAULT_CAPACITOR_220000pF_2_1!!CAP!!CAP_0402-0.22UF,16V,10%,X7R,A36096-155!!
S!C4D47!71!DEFAULT_CAPACITOR_220000pF_2_1!!CAP!!CAP_0402-0.22UF,16V,10%,X7R,A36096-155!!
S!C4C5!83!DEFAULT_CAPACITOR_220000pF_2_1!!CAP!!CAP_0402-0.22UF,16V,10%,X7R,A36096-155!!
S!C7G34!29!DEFAULT_CAPACITOR_220000pF_2_1!!CAP!!CAP_0402-0.22UF,16V,10%,X7R,A36096-155!!
S!C7G41!14!DEFAULT_CAPACITOR_220000pF_2_1!!CAP!!CAP_0402-0.22UF,16V,10%,X7R,A36096-155!!
S!C7A17!12!DEFAULT_CAPACITOR_220000pF_2_1!!CAP!!CAP_0402-0.22UF,16V,10%,X7R,A36096-155!!
S!C7A25!31!DEFAULT_CAPACITOR_220000pF_2_1!!CAP!!CAP_0402-0.22UF,16V,10%,X7R,A36096-155!!
S!C1B21!86!DEFAULT_CAPACITOR_220000pF_2_1!!CAP!!CAP_0402-0.22UF,16V,10%,X7R,A36096-155!!
S!C1A13!80!DEFAULT_CAPACITOR_220000pF_2_1!!CAP!!CAP_0402-0.22UF,16V,10%,X7R,A36096-155!!
S!C1G5!2!DEFAULT_CAPACITOR_220000pF_2_1!!CAP!!CAP_0402-0.22UF,16V,10%,X7R,A36096-155!!
S!C1G29!9!DEFAULT_CAPACITOR_220000pF_2_1!!CAP!!CAP_0402-0.22UF,16V,10%,X7R,A36096-155!!
S!C1E25!!DEFAULT_CAPACITOR_220000pF_2_1!!CAP!!CAP_0402-0.22UF,16V,10%,X7R,A36096-155!!
S!C1E7!8!DEFAULT_CAPACITOR_220000pF_2_1!!CAP!!CAP_0402-0.22UF,16V,10%,X7R,A36096-155!!
S!C1D16!7!DEFAULT_CAPACITOR_220000pF_2_1!!CAP!!CAP_0402-0.22UF,16V,10%,X7R,A36096-155!!
S!C1D6!!DEFAULT_CAPACITOR_220000pF_2_1!!CAP!!CAP_0402-0.22UF,16V,10%,X7R,A36096-155!!
S!C1C4!!DEFAULT_CAPACITOR_220000pF_2_1!!CAP!!CAP_0402-0.22UF,16V,10%,X7R,A36096-155!!
S!C1F3!!DEFAULT_CAPACITOR_220000pF_2_1!!CAP!!CAP_0402-0.22UF,16V,10%,X7R,A36096-155!!
S!C1F12!!DEFAULT_CAPACITOR_220000pF_2_1!!CAP!!CAP_0402-0.22UF,16V,10%,X7R,A36096-155!!
S!C1F11!!DEFAULT_CAPACITOR_220000pF_2_1!!CAP!!CAP_0402-0.22UF,16V,10%,X7R,A36096-155!!
S!C1F8!!DEFAULT_CAPACITOR_220000pF_2_1!!CAP!!CAP_0402-0.22UF,16V,10%,X7R,A36096-155!!
S!C1F18!!DEFAULT_CAPACITOR_220000pF_2_1!!CAP!!CAP_0402-0.22UF,16V,10%,X7R,A36096-155!!
S!C1F17!!DEFAULT_CAPACITOR_220000pF_2_1!!CAP!!CAP_0402-0.22UF,16V,10%,X7R,A36096-155!!
S!C1F14!!DEFAULT_CAPACITOR_220000pF_2_1!!CAP!!CAP_0402-0.22UF,16V,10%,X7R,A36096-155!!
S!C1F5!!DEFAULT_CAPACITOR_220000pF_2_1!!CAP!!CAP_0402-0.22UF,16V,10%,X7R,A36096-155!!
S!C1F4!!DEFAULT_CAPACITOR_220000pF_2_1!!CAP!!CAP_0402-0.22UF,16V,10%,X7R,A36096-155!!
S!C1F2!!DEFAULT_CAPACITOR_220000pF_2_1!!CAP!!CAP_0402-0.22UF,16V,10%,X7R,A36096-155!!
S!C1F13!!DEFAULT_CAPACITOR_220000pF_2_1!!CAP!!CAP_0402-0.22UF,16V,10%,X7R,A36096-155!!
S!C1F10!!DEFAULT_CAPACITOR_220000pF_2_1!!CAP!!CAP_0402-0.22UF,16V,10%,X7R,A36096-155!!
S!C1F6!!DEFAULT_CAPACITOR_220000pF_2_1!!CAP!!CAP_0402-0.22UF,16V,10%,X7R,A36096-155!!
S!C1F20!!DEFAULT_CAPACITOR_220000pF_2_1!!CAP!!CAP_0402-0.22UF,16V,10%,X7R,A36096-155!!
S!C1F16!!DEFAULT_CAPACITOR_220000pF_2_1!!CAP!!CAP_0402-0.22UF,16V,10%,X7R,A36096-155!!
S!C1F15!!DEFAULT_CAPACITOR_220000pF_2_1!!CAP!!CAP_0402-0.22UF,16V,10%,X7R,A36096-155!!
S!C1D33!!DEFAULT_CAPACITOR_220000pF_2_1!!CAP!!CAP_0402-0.22UF,16V,10%,X7R,A36096-155!!
S!C7C18!339!DEFAULT_CAPACITOR_220000pF_2_1!!CAP!!CAP_0402-0.22UF,16V,10%,X7R,A36096-155!!
S!C9G5!!DEFAULT_CAPACITOR_1e+06pF_2_1!!CAP!!CAP_0402-1.0UF,16V,10%,X7S,G71842-007!!
S!C7A14!!DEFAULT_CAPACITOR_1e+08pF_2_1!!CAP!!CAP_1210-100UF,16V,20%,X5R,644066-127!!
S!C7A13!!DEFAULT_CAPACITOR_1e+08pF_2_1!!CAP!!CAP_1210-100UF,16V,20%,X5R,644066-127!!
S!C7C7!428!DEFAULT_CAPACITOR_1e+08pF_2_1!!CAP!!CAP_1210-100UF,16V,20%,X5R,644066-127!!
S!C7C8!429!DEFAULT_CAPACITOR_1e+08pF_2_1!!CAP!!CAP_1210-100UF,16V,20%,X5R,644066-127!!
S!C4E8!340!DEFAULT_CAPACITOR_470000pF_2_1!!CAP!!CAP_1210-100UF,16V,20%,X5R,644066-127!!
S!C4E9!339!DEFAULT_CAPACITOR_220000pF_2_1!!CAP!!CAP_1210-100UF,16V,20%,X5R,644066-127!!
S!C4E14!377!DEFAULT_CAPACITOR_1e+08pF_2_1!!CAP!!CAP_1210-100UF,16V,20%,X5R,644066-127!!
S!R2U42!!RES_0402-0.0_5%_1/16W_CHIP_G21A_0.0!!RES!!RES_0402-221,1.0%,1/16W,CHIP,G21796-271!!
S!R2U44!4!RES_0402-0.0_5%_1/16W_CHIP_G21A_0.0!!RES!!RES_0402-221,1.0%,1/16W,CHIP,G21796-271!!
S!R9F28!!!!RES!!RES_0402-221,1.0%,1/16W,CHIP,G21796-271!!
S!R9A20!!DEFAULT_RESISTOR_221.000000OHM_2_1!!RES!!RES_0402-221,1.0%,1/16W,CHIP,G21796-271!!
S!R6B3!5!DEFAULT_RESISTOR_220.000000OHM_2_1!!RES!!RES_0402-221,1.0%,1/16W,CHIP,G21796-271!!
S!R6N10!!DEFAULT_RESISTOR_220.000000OHM_2_1!!RES!!RES_0402-221,1.0%,1/16W,CHIP,G21796-271!!
S!R1C1!!DEFAULT_RESISTOR_220.000000OHM_2_1!!RES!!RES_0402-221,1.0%,1/16W,CHIP,G21796-271!!
S!R3B1!!DEFAULT_RESISTOR_220.000000OHM_2_1!!RES!!RES_0402-221,1.0%,1/16W,CHIP,G21796-271!!
S!R9E24!!DEFAULT_RESISTOR_220.000000OHM_2_1!!RES!!RES_0402-221,1.0%,1/16W,CHIP,G21796-271!!
S!R1L33!!DEFAULT_RESISTOR_220.000000OHM_2_1!!RES!!RES_0402-221,1.0%,1/16W,CHIP,G21796-271!!
S!R8C16!!DEFAULT_RESISTOR_3300OHM_2_1!!RES!!RES_0402-3.3K,5%,1/16W,CHIP,G21497-013!!
S!R8C15!!DEFAULT_RESISTOR_3300OHM_2_1!!RES!!RES_0402-3.3K,5%,1/16W,CHIP,G21497-013!!
S!R8B24!!DEFAULT_RESISTOR_3300OHM_2_1!!RES!!RES_0402-3.3K,5%,1/16W,CHIP,G21497-013!!
S!R8B26!!DEFAULT_RESISTOR_3300OHM_2_1!!RES!!RES_0402-3.3K,5%,1/16W,CHIP,G21497-013!!
S!R8A12!37!DEFAULT_RESISTOR_475.000000OHM_2_1!!RES!!RES_0603-475.0,1%,1/10W,CHIP,G22026-030!!
S!R9P12!!!!RES!!RES_0402-4.99K,1%,1/16W,CHIP,G21796-013!!
S!R9E23!!DEFAULT_RESISTOR_4990OHM_2_1!!RES!!RES_0402-4.99K,1%,1/16W,CHIP,G21796-013!!
S!C9F2!!!!CAP!!CAP_1210-47UF,16V,20%,EMPTY,D38464-007!!
S!C9E6!!!!CAP!!CAP_1210-47UF,16V,20%,EMPTY,D38464-007!!
S!Y7C1!!!!CRYSTAL!!CRYSTAL_2013-48.000MHZ,IC,D71700-058!!
S!Y8F1!!!!CRYSTAL!!CRYSTAL_2013LF-25.000MHZ,IC,D71700-033!!
S!Y7C2!!!!CRYSTAL!!CRYSTAL_SM-32.768KHZ,IC,C13544-023!!
S!CR1L1!!!!DIODE!!DIODE_SM-1N4148W,IC,D89194-001!!
S!CR1L2!!!!DIODE!!DIODE_SM-1N4148W,IC,D89194-001!!
S!CR1L3!!!!DIODE!!DIODE_SM-1N4148W,IC,D89194-001!!
S!CR1L4!!!!DIODE!!DIODE_SM-1N4148W,IC,D89194-001!!
S!FB6P1!!DEFAULT_RESISTOR_600.000000OHM_2_1!!FERRITE!!FERRITE_SMLF-600,FB,656554-043!!
S!FB2T2!!DEFAULT_RESISTOR_600.000000OHM_2_1!!FERRITE!!FERRITE_SMLF-600,FB,656554-043!!
S!EU8F2!!!!ICS9FGP204!!ICS9FGP204_MLFP-IC,E95226-001!!
S!R6P25!!DEFAULT_RESISTOR_2.200000OHM_2_1!!RES!!RES_0603-2.2,1.0%,1/10W,CHIP,G22026-127!!
S!R3D14!!DEFAULT_RESISTOR_2.200000OHM_2_1!!RES!!RES_0603-2.2,1.0%,1/10W,CHIP,G22026-127!!
S!R2T21!!DEFAULT_RESISTOR_2.200000OHM_2_1!!RES!!RES_0603-2.2,1.0%,1/10W,CHIP,G22026-127!!
S!R2T52!!DEFAULT_RESISTOR_2.200000OHM_2_1!!RES!!RES_0603-2.2,1.0%,1/10W,CHIP,G22026-127!!
S!R2T23!!DEFAULT_RESISTOR_2.200000OHM_2_1!!RES!!RES_0603-2.2,1.0%,1/10W,CHIP,G22026-127!!
S!C9E7!!DEFAULT_CAPACITOR_39000pF_2_1!!CAP!!CAP_0402LF-0.039UF,25V,10%,X7R,A36096-063!!
S!DS9A2!!!!LED!!LED_1NCLF-GREEN,IC,C96565-011!!
S!EU9E1!!!!SPRINGVILLE!!SPRINGVILLE_SM1-IC,G47144-004!!
S!TH1A1!!!!MTG_KEYHOLE!!MTG_KEYHOLE_TH-EMPTY,NA!!
S!TH4A1!!!!MTG_KEYHOLE!!MTG_KEYHOLE_TH-EMPTY,NA!!
S!TH7A1!!!!MTG_KEYHOLE!!MTG_KEYHOLE_TH-EMPTY,NA!!
S!TH9A1!!!!MTG_KEYHOLE!!MTG_KEYHOLE_TH-EMPTY,NA!!
S!TH4G1!!!!MTG_KEYHOLE!!MTG_KEYHOLE_TH-EMPTY,NA!!
S!TH7G1!!!!MTG_KEYHOLE!!MTG_KEYHOLE_TH-EMPTY,NA!!
S!TH9G1!!!!MTG_KEYHOLE!!MTG_KEYHOLE_TH-EMPTY,NA!!
S!R6P33!387!RES_0402-110_1%_1/16W_EMPTY_G2A_NA!!RES!!RES_0402-110,1%,1/16W,EMPTY,G21796-203!!
S!R8B9!!DEFAULT_RESISTOR_113.000000OHM_2_1!!RES!!RES_0402-113,1%,1/16W,CHIP,G21796-341!!
S!R1D42!9!DEFAULT_RESISTOR_11000OHM_2_1!!RES!!RES_0402-11K,1%,1/16W,CHIP,G21796-220!!
S!R1U49!!DEFAULT_RESISTOR_47000OHM_2_1!!RES!!RES_0402-2.7K,1%,1/16W,CHIP,G21796-344!!
S!R9G35!!!!RES!!RES_0402-2.7K,1%,1/16W,CHIP,G21796-344!!
S!R1T4!!!!RES!!RES_0402-2.7K,1%,1/16W,CHIP,G21796-344!!
S!R1U23!!!!RES!!RES_0402-2.7K,1%,1/16W,CHIP,G21796-344!!
S!R1U24!!!!RES!!RES_0402-2.7K,1%,1/16W,CHIP,G21796-344!!
S!R9P4!!DEFAULT_RESISTOR_10000OHM_2_1!!RES!!RES_0402-2.7K,1%,1/16W,CHIP,G21796-344!!
S!R9P20!!DEFAULT_RESISTOR_10000OHM_2_1!!RES!!RES_0402-2.7K,1%,1/16W,CHIP,G21796-344!!
S!R9G8!!DEFAULT_RESISTOR_2700OHM_2_1!!RES!!RES_0402-2.7K,1%,1/16W,CHIP,G21796-344!!
S!XLU1!!!!SOCKET_P_MECH_A!!SOCKET_P_MECH_A_LEFT-P0,PLASTIC,H37604-201!!
S!XLU2!!!!SOCKET_P_MECH_A!!SOCKET_P_MECH_A_LEFT-P0,PLASTIC,H37604-201!!
S!XRU1!!!!SOCKET_P_MECH_A!!SOCKET_P_MECH_A_RIGHT-P0,PLASTIC,H37604-101!!
S!XRU2!!!!SOCKET_P_MECH_A!!SOCKET_P_MECH_A_RIGHT-P0,PLASTIC,H37604-101!!
S!FB1U1!!DEFAULT_RESISTOR_300.000000OHM_2_1!!FERRITE!!FERRITE_SMLF-300,FB,693286-046!!
S!FB9F1!!DEFAULT_RESISTOR_300.000000OHM_2_1!!FERRITE!!FERRITE_SMLF-300,FB,693286-046!!
S!FB1T2!!DEFAULT_RESISTOR_300.000000OHM_2_1!!FERRITE!!FERRITE_SMLF-300,FB,693286-046!!
S!L7A4!24!DEFAULT_INDUCTOR_300.000000nH_2_1!!INDUCTOR!!INDUCTOR_SM-0.3UH,IND,D92183-036!!
S!L7A2!!DEFAULT_INDUCTOR_300.000000nH_2_1!!INDUCTOR!!INDUCTOR_SM-0.3UH,IND,D92183-036!!
S!L4C2!99!DEFAULT_INDUCTOR_300.000000nH_2_1!!INDUCTOR!!INDUCTOR_SM-0.3UH,IND,D92183-036!!
S!L1C1!!DEFAULT_INDUCTOR_300.000000nH_2_1!!INDUCTOR!!INDUCTOR_SM-0.3UH,IND,D92183-036!!
S!L7B1!30!DEFAULT_INDUCTOR_470.000000nH_2_1!!INDUCTOR!!INDUCTOR_SM-0.47UH,IND,E13358-018!!
S!L4G1!30!DEFAULT_INDUCTOR_470.000000nH_2_1!!INDUCTOR!!INDUCTOR_SM-0.47UH,IND,E13358-018!!
S!L4A1!30!DEFAULT_INDUCTOR_470.000000nH_2_1!!INDUCTOR!!INDUCTOR_SM-0.47UH,IND,E13358-018!!
S!L7F1!30!DEFAULT_INDUCTOR_470.000000nH_2_1!!INDUCTOR!!INDUCTOR_SM-0.47UH,IND,E13358-018!!
S!J1D1!!!!CONN12_G98257001!!CONN12_G98257001_THMT-CONN,G98257-001!!
S!J1E1!!!!CONN12_G98257001!!CONN12_G98257001_THMT-CONN,G98257-001!!
S!FB3M1!5!DEFAULT_RESISTOR_120.000000OHM_2_1!!FERRITE!!FERRITE_SM-120,FB,693286-027!!
S!FB3M2!2!DEFAULT_RESISTOR_120.000000OHM_2_1!!FERRITE!!FERRITE_SM-120,FB,693286-027!!
S!FB3M3!!DEFAULT_RESISTOR_120.000000OHM_2_1!!FERRITE!!FERRITE_SM-120,FB,693286-027!!
S!FB3M4!!DEFAULT_RESISTOR_120.000000OHM_2_1!!FERRITE!!FERRITE_SM-120,FB,693286-027!!
S!FB2M1!!DEFAULT_RESISTOR_120.000000OHM_2_1!!FERRITE!!FERRITE_SM-120,FB,693286-027!!
S!FB2M2!5!DEFAULT_RESISTOR_120.000000OHM_2_1!!FERRITE!!FERRITE_SM-120,FB,693286-027!!
S!R9G3!!DEFAULT_RESISTOR_330.000000OHM_2_1!!RES!!RES_0402-330.0,5%,1/16W,CHIP,G21497-028!!
S!R9G2!!DEFAULT_RESISTOR_330.000000OHM_2_1!!RES!!RES_0402-330.0,5%,1/16W,CHIP,G21497-028!!
S!R9G1!!DEFAULT_RESISTOR_330.000000OHM_2_1!!RES!!RES_0402-330.0,5%,1/16W,CHIP,G21497-028!!
S!R1T10!!DEFAULT_RESISTOR_1000.000000OHM_2_1!!RES!!RES_0402-1.00K,1%,1/16W,EMPTY,G21796-026!!
S!R1U17!!DEFAULT_RESISTOR_1000.000000OHM_2_1!!RES!!RES_0402-1.00K,1%,1/16W,EMPTY,G21796-026!!
S!R1U18!!DEFAULT_RESISTOR_1000.000000OHM_2_1!!RES!!RES_0402-1.00K,1%,1/16W,EMPTY,G21796-026!!
S!R7E19!!!!RES!!RES_0402-1.00K,1%,1/16W,EMPTY,G21796-026!!
S!R1M23!!!!RES!!RES_0402-1.00K,1%,1/16W,EMPTY,G21796-026!!
S!R2N14!!!!RES!!RES_0402-1.00K,1%,1/16W,EMPTY,G21796-026!!
S!R7D19!!RES_0402-1.00K_1%_1/16W_EMPTY_A_NA!!RES!!RES_0402-1.00K,1%,1/16W,EMPTY,G21796-026!!
S!R8E6!!RES_0402-1.00K_1%_1/16W_EMPTY_A_NA!!RES!!RES_0402-1.00K,1%,1/16W,EMPTY,G21796-026!!
S!R3N17!!RES_0402-1.00K_1%_1/16W_EMPTY_A_NA!!RES!!RES_0402-1.00K,1%,1/16W,EMPTY,G21796-026!!
S!R2N24!!RES_0402-1.00K_1%_1/16W_EMPTY_A_NA!!RES!!RES_0402-1.00K,1%,1/16W,EMPTY,G21796-026!!
S!R2P11!!RES_0402-1.00K_1%_1/16W_EMPTY_A_NA!!RES!!RES_0402-1.00K,1%,1/16W,EMPTY,G21796-026!!
S!R9A1!!RES_0402-1.00K_1%_1/16W_EMPTY_A_NA!!RES!!RES_0402-1.00K,1%,1/16W,EMPTY,G21796-026!!
S!R8F35!!RES_0402-1.00K_1%_1/16W_EMPTY_A_NA!!RES!!RES_0402-1.00K,1%,1/16W,EMPTY,G21796-026!!
S!R8C17!!RES_0402-1.00K_1%_1/16W_EMPTY_A_NA!!RES!!RES_0402-1.00K,1%,1/16W,EMPTY,G21796-026!!
S!R8E4!!RES_0402-1.00K_1%_1/16W_EMPTY_A_NA!!RES!!RES_0402-1.00K,1%,1/16W,EMPTY,G21796-026!!
S!R2R11!!RES_0402-1.00K_1%_1/16W_EMPTY_A_NA!!RES!!RES_0402-1.00K,1%,1/16W,EMPTY,G21796-026!!
S!R8D5!!RES_0402-1.00K_1%_1/16W_EMPTY_A_NA!!RES!!RES_0402-1.00K,1%,1/16W,EMPTY,G21796-026!!
S!R1E5!5!RES_0402-1.00K_1%_1/16W_EMPTY_A_NA!!RES!!RES_0402-1.00K,1%,1/16W,EMPTY,G21796-026!!
S!R4C3!104!RES_0402-1.00K_1%_1/16W_EMPTY_A_NA!YES!RES!!RES_0402-1.00K,1%,1/16W,EMPTY,G21796-026!!
S!R4E15!109!RES_0402-1.00K_1%_1/16W_EMPTY_A_NA!YES!RES!!RES_0402-1.00K,1%,1/16W,EMPTY,G21796-026!!
S!R1C6!!RES_0402-1.00K_1%_1/16W_EMPTY_A_NA!YES!RES!!RES_0402-1.00K,1%,1/16W,EMPTY,G21796-026!!
S!R2N10!!DEFAULT_RESISTOR_10000OHM_2_1!!RES!!RES_0402-1.0M,1%,1/16W,CHIP,G21796-021!!
S!R6L4!!!!RES!!RES_0402-1.0M,1%,1/16W,EMPTY,G21796-021!!
S!R6U3!!!!RES!!RES_0402-1.0M,1%,1/16W,EMPTY,G21796-021!!
S!R6U15!11!!!RES!!RES_0402-1.0M,1%,1/16W,EMPTY,G21796-021!!
S!R6L5!!!!RES!!RES_0402-1.0M,1%,1/16W,EMPTY,G21796-021!!
S!R7C11!!!!RES!!RES_0402-1.0M,1%,1/16W,EMPTY,G21796-021!!
S!R1B9!102!DEFAULT_RESISTOR_100000OHM_2_1!!RES!!RES_0402-1.5K,1%,1/16W,CHIP,G21796-003!!
S!R1C16!!DEFAULT_RESISTOR_1000.000000OHM_2_1!!RES!!RES_0402-1.5K,1%,1/16W,CHIP,G21796-003!!
S!R1G24!13!DEFAULT_RESISTOR_100000OHM_2_1!!RES!!RES_0402-1.5K,1%,1/16W,CHIP,G21796-003!!
S!R2L10!!DEFAULT_RESISTOR_100000OHM_2_1!!RES!!RES_0402-1.5K,1%,1/16W,CHIP,G21796-003!!
S!R3P16!397!DEFAULT_RESISTOR_100000OHM_2_1!!RES!!RES_0402-1.5K,1%,1/16W,CHIP,G21796-003!!
S!R4D32!28!DEFAULT_RESISTOR_1000.000000OHM_2_1!!RES!!RES_0402-1.5K,1%,1/16W,CHIP,G21796-003!!
S!R4D57!346!DEFAULT_RESISTOR_100000OHM_2_1!!RES!!RES_0402-1.5K,1%,1/16W,CHIP,G21796-003!!
S!R7A16!!DEFAULT_RESISTOR_100000OHM_2_1!!RES!!RES_0402-1.5K,1%,1/16W,CHIP,G21796-003!!
S!R7G3!90!DEFAULT_RESISTOR_1000.000000OHM_2_1!!RES!!RES_0402-1.5K,1%,1/16W,CHIP,G21796-003!!
S!R1U52!!!!RES!!RES_0402-1.5K,1%,1/16W,CHIP,G21796-003!!
S!R9T6!!DEFAULT_RESISTOR_10000OHM_2_1!!RES!!RES_0402-15.0K,1%,1/16W,CHIP,G21796-107!!
S!R9P18!31!DEFAULT_RESISTOR_15000OHM_2_1!!RES!!RES_0402-15.0K,1%,1/16W,CHIP,G21796-107!!
S!R9M17!!DEFAULT_RESISTOR_2000OHM_2_1!!RES!!RES_0402-2.0K,1%,1/16W,CHIP,G21796-001!!
S!R9M16!!DEFAULT_RESISTOR_2000OHM_2_1!!RES!!RES_0402-2.0K,1%,1/16W,CHIP,G21796-001!!
S!R8D17!!DEFAULT_RESISTOR_3300OHM_2_1!!RES!!RES_0402-2.0K,1%,1/16W,CHIP,G21796-001!!
S!R8D15!!DEFAULT_RESISTOR_3300OHM_2_1!!RES!!RES_0402-2.0K,1%,1/16W,CHIP,G21796-001!!
S!R3N3!!DEFAULT_RESISTOR_10000OHM_2_1!!RES!!RES_0402-2.0K,1%,1/16W,CHIP,G21796-001!!
S!R2L12!!DEFAULT_RESISTOR_2000OHM_2_1!!RES!!RES_0402-2.0K,1%,1/16W,CHIP,G21796-001!!
S!R2L5!!DEFAULT_RESISTOR_2000OHM_2_1!!RES!!RES_0402-2.0K,1%,1/16W,CHIP,G21796-001!!
S!R2L4!!DEFAULT_RESISTOR_2000OHM_2_1!!RES!!RES_0402-2.0K,1%,1/16W,CHIP,G21796-001!!
S!R2L15!!DEFAULT_RESISTOR_2000OHM_2_1!!RES!!RES_0402-2.0K,1%,1/16W,CHIP,G21796-001!!
S!R2L6!!DEFAULT_RESISTOR_2000OHM_2_1!!RES!!RES_0402-2.0K,1%,1/16W,CHIP,G21796-001!!
S!R2L11!!DEFAULT_RESISTOR_2000OHM_2_1!!RES!!RES_0402-2.0K,1%,1/16W,CHIP,G21796-001!!
S!R2L21!!DEFAULT_RESISTOR_2000OHM_2_1!!RES!!RES_0402-2.0K,1%,1/16W,CHIP,G21796-001!!
S!R2L23!!DEFAULT_RESISTOR_2000OHM_2_1!!RES!!RES_0402-2.0K,1%,1/16W,CHIP,G21796-001!!
S!R1L1!!DEFAULT_RESISTOR_2000OHM_2_1!!RES!!RES_0402-2.0K,1%,1/16W,CHIP,G21796-001!!
S!R9A7!!RES_0402-4.75K_1%_1/16W_CHIP_GA_4.75K!!RES!!RES_0402-2.21K,1%,1/16W,CHIP,G21796-112!!
S!R1R18!!!!RES!!RES_0402-2.21K,1%,1/16W,CHIP,G21796-112!!
S!R1R19!!!!RES!!RES_0402-2.21K,1%,1/16W,CHIP,G21796-112!!
S!R1R20!!!!RES!!RES_0402-2.21K,1%,1/16W,CHIP,G21796-112!!
S!R1R21!!!!RES!!RES_0402-2.21K,1%,1/16W,CHIP,G21796-112!!
S!R1R16!!!!RES!!RES_0402-2.21K,1%,1/16W,CHIP,G21796-112!!
S!R1R17!!!!RES!!RES_0402-2.21K,1%,1/16W,CHIP,G21796-112!!
S!R1R23!!!!RES!!RES_0402-2.21K,1%,1/16W,CHIP,G21796-112!!
S!R1R22!!!!RES!!RES_0402-2.21K,1%,1/16W,CHIP,G21796-112!!
S!R4U2!!DEFAULT_RESISTOR_2210OHM_2_1!!RES!!RES_0402-2.21K,1%,1/16W,CHIP,G21796-112!!
S!R8F23!!DEFAULT_RESISTOR_2210OHM_2_1!!RES!!RES_0402-2.21K,1%,1/16W,CHIP,G21796-112!!
S!R2T29!!DEFAULT_RESISTOR_2210OHM_2_1!!RES!!RES_0402-2.21K,1%,1/16W,CHIP,G21796-112!!
S!R9A16!!DEFAULT_RESISTOR_2210OHM_2_1!!RES!!RES_0402-2.21K,1%,1/16W,CHIP,G21796-112!!
S!R9A12!!DEFAULT_RESISTOR_2210OHM_2_1!!RES!!RES_0402-2.21K,1%,1/16W,CHIP,G21796-112!!
S!R8G6!!!!RES!!RES_0402-2.26K,1.0%,1/16W,EMPTY,G21796-311!!
S!R8G3!!!!RES!!RES_0402-2.26K,1.0%,1/16W,EMPTY,G21796-311!!
S!R2U13!!!!RES!!RES_0402-2.26K,1.0%,1/16W,EMPTY,G21796-311!!
S!R2U5!!!!RES!!RES_0402-2.26K,1.0%,1/16W,EMPTY,G21796-311!!
S!R2L24!!!!RES!!RES_0402-2.26K,1.0%,1/16W,EMPTY,G21796-311!!
S!R6P49!379!!!RES!!RES_0402-2.26K,1.0%,1/16W,EMPTY,G21796-311!!
S!R3N23!405!!!RES!!RES_0402-2.26K,1.0%,1/16W,EMPTY,G21796-311!!
S!R7A9!!!!RES!!RES_0402-2.26K,1.0%,1/16W,EMPTY,G21796-311!!
S!R1G6!5!!!RES!!RES_0402-2.26K,1.0%,1/16W,EMPTY,G21796-311!!
S!R1B13!114!!!RES!!RES_0402-2.26K,1.0%,1/16W,EMPTY,G21796-311!!
S!R4E20!45!!!RES!!RES_0402-2.26K,1.0%,1/16W,EMPTY,G21796-311!!
S!R7F36!47!!!RES!!RES_0402-2.26K,1.0%,1/16W,EMPTY,G21796-311!!
S!R4D31!13!!!RES!!RES_0402-2.26K,1.0%,1/16W,EMPTY,G21796-311!!
S!R1D53!!!!RES!!RES_0402-2.26K,1.0%,1/16W,EMPTY,G21796-311!!
S!R1C18!!!!RES!!RES_0402-2.26K,1.0%,1/16W,EMPTY,G21796-311!!
S!R1R7!!DEFAULT_RESISTOR_3320OHM_2_1!!RES!!RES_0402-20.0K,1%,1/16W,CHIP,G21796-040!!
S!R7F13!9!DEFAULT_RESISTOR_15000OHM_2_1!!RES!!RES_0402-20.0K,1%,1/16W,CHIP,G21796-040!!
S!R7B15!9!DEFAULT_RESISTOR_20000OHM_2_1!!RES!!RES_0402-20.0K,1%,1/16W,CHIP,G21796-040!!
S!R4G7!9!DEFAULT_RESISTOR_20000OHM_2_1!!RES!!RES_0402-20.0K,1%,1/16W,CHIP,G21796-040!!
S!R4B5!9!DEFAULT_RESISTOR_20000OHM_2_1!!RES!!RES_0402-20.0K,1%,1/16W,CHIP,G21796-040!!
S!R9A5!!DEFAULT_RESISTOR_20000OHM_2_1!YES!RES!!RES_0402-20.0K,1%,1/16W,CHIP,G21796-040!!
S!R3N4!!DEFAULT_RESISTOR_20000OHM_2_1!YES!RES!!RES_0402-20.0K,1%,1/16W,CHIP,G21796-040!!
S!R7C10!!DEFAULT_RESISTOR_20000OHM_2_1!YES!RES!!RES_0402-20.0K,1%,1/16W,CHIP,G21796-040!!
S!R8F33!!RES_0402-0.0_5%_1/16W_CHIP_G21A_0.0!!RES!!RES_0402-22.1,1.0%,1/16W,CHIP,G21796-250!!
S!R8F30!!DEFAULT_RESISTOR_22.000000OHM_2_1!!RES!!RES_0402-22.1,1.0%,1/16W,CHIP,G21796-250!!
S!R2T46!!DEFAULT_RESISTOR_10.000000OHM_2_1!!RES!!RES_0402-22.1,1.0%,1/16W,CHIP,G21796-250!!
S!R2T42!!DEFAULT_RESISTOR_10.000000OHM_2_1!!RES!!RES_0402-22.1,1.0%,1/16W,CHIP,G21796-250!!
S!R4D46!349!RES_0402-0.0_5%_1/16W_CHIP_G21A_0.0!!RES!!RES_0402-22.1,1.0%,1/16W,CHIP,G21796-250!!
S!R9F11!!DEFAULT_RESISTOR_22.100000OHM_2_1!!RES!!RES_0402-22.1,1.0%,1/16W,CHIP,G21796-250!!
S!R1T9!!DEFAULT_RESISTOR_22.100000OHM_2_1!!RES!!RES_0402-22.1,1.0%,1/16W,CHIP,G21796-250!!
S!R8A11!!DEFAULT_RESISTOR_22.100000OHM_2_1!!RES!!RES_0402-22.1,1.0%,1/16W,CHIP,G21796-250!!
S!R8F10!!DEFAULT_RESISTOR_22.100000OHM_2_1!!RES!!RES_0402-22.1,1.0%,1/16W,CHIP,G21796-250!!
S!R7E15!!DEFAULT_RESISTOR_22.100000OHM_2_1!!RES!!RES_0402-22.1,1.0%,1/16W,CHIP,G21796-250!!
S!R1C30!!DEFAULT_RESISTOR_22.100000OHM_2_1!!RES!!RES_0402-22.1,1.0%,1/16W,CHIP,G21796-250!!
S!R7B12!!DEFAULT_RESISTOR_22.100000OHM_2_1!!RES!!RES_0402-22.1,1.0%,1/16W,CHIP,G21796-250!!
S!R4G12!!DEFAULT_RESISTOR_22.100000OHM_2_1!!RES!!RES_0402-22.1,1.0%,1/16W,CHIP,G21796-250!!
S!R7F16!!DEFAULT_RESISTOR_22.100000OHM_2_1!!RES!!RES_0402-22.1,1.0%,1/16W,CHIP,G21796-250!!
S!R4B7!!DEFAULT_RESISTOR_22.100000OHM_2_1!!RES!!RES_0402-22.1,1.0%,1/16W,CHIP,G21796-250!!
S!R4D63!!DEFAULT_RESISTOR_22.100000OHM_2_1!!RES!!RES_0402-22.1,1.0%,1/16W,CHIP,G21796-250!!
S!R7F24!102!RES_0402-0.0_5%_1/16W_CHIP_G21A_0.0!!RES!!RES_0402-22.1,1.0%,1/16W,CHIP,G21796-250!!
S!R3M3!!RES_0402-0.0_5%_1/16W_CHIP_G21A_0.0!!RES!!RES_0402-22.1,1.0%,1/16W,CHIP,G21796-250!!
S!R1G12!10!RES_0402-0.0_5%_1/16W_CHIP_G21A_0.0!!RES!!RES_0402-22.1,1.0%,1/16W,CHIP,G21796-250!!
S!R1B5!110!RES_0402-0.0_5%_1/16W_CHIP_G21A_0.0!!RES!!RES_0402-22.1,1.0%,1/16W,CHIP,G21796-250!!
S!R3P20!399!RES_0402-0.0_5%_1/16W_CHIP_G21A_0.0!!RES!!RES_0402-22.1,1.0%,1/16W,CHIP,G21796-250!!
S!R2L16!!RES_0402-0.0_5%_1/16W_CHIP_G21A_0.0!!RES!!RES_0402-22.1,1.0%,1/16W,CHIP,G21796-250!!
S!R2T41!!DEFAULT_RESISTOR_22.000000OHM_2_1!!RES!!RES_0402-22.1,1.0%,1/16W,CHIP,G21796-250!!
S!R1T26!!DEFAULT_RESISTOR_22.000000OHM_2_1!!RES!!RES_0402-22.1,1.0%,1/16W,CHIP,G21796-250!!
S!R2T45!!DEFAULT_RESISTOR_22.000000OHM_2_1!!RES!!RES_0402-22.1,1.0%,1/16W,CHIP,G21796-250!!
S!R8F28!!DEFAULT_RESISTOR_22.000000OHM_2_1!!RES!!RES_0402-22.1,1.0%,1/16W,CHIP,G21796-250!!
S!R8F31!!DEFAULT_RESISTOR_22.000000OHM_2_1!!RES!!RES_0402-22.1,1.0%,1/16W,CHIP,G21796-250!!
S!R9E17!!DEFAULT_RESISTOR_22.000000OHM_2_1!!RES!!RES_0402-22.1,1.0%,1/16W,CHIP,G21796-250!!
S!R9E19!!DEFAULT_RESISTOR_22.000000OHM_2_1!!RES!!RES_0402-22.1,1.0%,1/16W,CHIP,G21796-250!!
S!R1T28!!DEFAULT_RESISTOR_22.000000OHM_2_1!!RES!!RES_0402-22.1,1.0%,1/16W,CHIP,G21796-250!!
S!R9F1!!DEFAULT_RESISTOR_22.000000OHM_2_1!!RES!!RES_0402-22.1,1.0%,1/16W,CHIP,G21796-250!!
S!R8E7!!DEFAULT_RESISTOR_22.100000OHM_2_1!!RES!!RES_0402-22.1,1.0%,1/16W,CHIP,G21796-250!!
S!R8F27!!DEFAULT_RESISTOR_22.100000OHM_2_1!!RES!!RES_0402-22.1,1.0%,1/16W,CHIP,G21796-250!!
S!R9E7!!DEFAULT_RESISTOR_3320OHM_2_1!!RES!!RES_0402-3.32K,1%,1/16W,CHIP,G21796-027!!
S!R1R3!!DEFAULT_RESISTOR_3320OHM_2_1!!RES!!RES_0402-3.32K,1%,1/16W,CHIP,G21796-027!!
S!R1R9!!DEFAULT_RESISTOR_3320OHM_2_1!!RES!!RES_0402-3.32K,1%,1/16W,CHIP,G21796-027!!
S!R9F5!!DEFAULT_RESISTOR_3320OHM_2_1!!RES!!RES_0402-3.32K,1%,1/16W,CHIP,G21796-027!!
S!R1U28!!DEFAULT_RESISTOR_3480OHM_2_1!!RES!!RES_0402-3.48K,1.0%,1/16W,CHIP,G21796-279!!
S!R1U44!!DEFAULT_RESISTOR_3480OHM_2_1!!RES!!RES_0402-3.48K,1.0%,1/16W,CHIP,G21796-279!!
S!R1T13!!RES_0402-4.75K_1%_1/16W_CHIP_GA_4.75K!!RES!!RES_0402-4.75K,1%,1/16W,EMPTY,G21796-072!!
S!R1T18!!RES_0402-4.75K_1%_1/16W_CHIP_GA_4.75K!!RES!!RES_0402-4.75K,1%,1/16W,EMPTY,G21796-072!!
S!R7C22!!RES_0402-4.75K_1%_1/16W_CHIP_GA_4.75K!!RES!!RES_0402-4.75K,1%,1/16W,EMPTY,G21796-072!!
S!R7E18!!!!RES!!RES_0402-4.75K,1%,1/16W,EMPTY,G21796-072!!
S!R1T17!!RES_0402-4.75K_1%_1/16W_CHIP_GA_4.75K!!RES!!RES_0402-4.75K,1%,1/16W,EMPTY,G21796-072!!
S!R1L19!!DEFAULT_RESISTOR_4700OHM_2_1!!RES!!RES_0402-4.75K,1%,1/16W,EMPTY,G21796-072!!
S!R8E12!!DEFAULT_RESISTOR_4750OHM_2_1!!RES!!RES_0402-4.75K,1%,1/16W,EMPTY,G21796-072!!
S!R3N2!!DEFAULT_RESISTOR_4750OHM_2_1!!RES!!RES_0402-4.75K,1%,1/16W,EMPTY,G21796-072!!
S!R6P22!!DEFAULT_RESISTOR_4700OHM_2_1!!RES!!RES_0402-4.75K,1%,1/16W,EMPTY,G21796-072!!
S!R9F49!!RES_0402-4.75K_1%_1/16W_EMPTY_A_NA!!RES!!RES_0402-4.75K,1%,1/16W,EMPTY,G21796-072!!
S!R9F48!!RES_0402-4.75K_1%_1/16W_EMPTY_A_NA!!RES!!RES_0402-4.75K,1%,1/16W,EMPTY,G21796-072!!
S!R9F36!!RES_0402-4.75K_1%_1/16W_EMPTY_A_NA!!RES!!RES_0402-4.75K,1%,1/16W,EMPTY,G21796-072!!
S!R9F17!!RES_0402-4.75K_1%_1/16W_EMPTY_A_NA!!RES!!RES_0402-4.75K,1%,1/16W,EMPTY,G21796-072!!
S!R1T20!!RES_0402-4.75K_1%_1/16W_EMPTY_A_NA!!RES!!RES_0402-4.75K,1%,1/16W,EMPTY,G21796-072!!
S!R1T22!!RES_0402-4.75K_1%_1/16W_EMPTY_A_NA!!RES!!RES_0402-4.75K,1%,1/16W,EMPTY,G21796-072!!
S!R1T21!!RES_0402-4.75K_1%_1/16W_EMPTY_A_NA!!RES!!RES_0402-4.75K,1%,1/16W,EMPTY,G21796-072!!
S!R9F37!!RES_0402-4.75K_1%_1/16W_EMPTY_A_NA!!RES!!RES_0402-4.75K,1%,1/16W,EMPTY,G21796-072!!
S!R1T19!!RES_0402-4.75K_1%_1/16W_EMPTY_A_NA!!RES!!RES_0402-4.75K,1%,1/16W,EMPTY,G21796-072!!
S!R9F38!!RES_0402-4.75K_1%_1/16W_EMPTY_A_NA!!RES!!RES_0402-4.75K,1%,1/16W,EMPTY,G21796-072!!
S!R9F10!!RES_0402-4.75K_1%_1/16W_EMPTY_A_NA!!RES!!RES_0402-4.75K,1%,1/16W,EMPTY,G21796-072!!
S!R1T16!!RES_0402-4.75K_1%_1/16W_EMPTY_A_NA!!RES!!RES_0402-4.75K,1%,1/16W,EMPTY,G21796-072!!
S!R9F18!!RES_0402-4.75K_1%_1/16W_EMPTY_A_NA!!RES!!RES_0402-4.75K,1%,1/16W,EMPTY,G21796-072!!
S!R9F19!!RES_0402-4.75K_1%_1/16W_EMPTY_A_NA!!RES!!RES_0402-4.75K,1%,1/16W,EMPTY,G21796-072!!
S!R9F39!!RES_0402-4.75K_1%_1/16W_EMPTY_A_NA!!RES!!RES_0402-4.75K,1%,1/16W,EMPTY,G21796-072!!
S!R1D29!1!RES_0402-4.75K_1%_1/16W_EMPTY_A_NA!YES!RES!!RES_0402-4.75K,1%,1/16W,EMPTY,G21796-072!!
S!R1D27!22!RES_0402-4.75K_1%_1/16W_EMPTY_A_NA!YES!RES!!RES_0402-4.75K,1%,1/16W,EMPTY,G21796-072!!
S!R6P23!!RES_0402-4.75K_1%_1/16W_EMPTY_A_NA!!RES!!RES_0402-4.75K,1%,1/16W,EMPTY,G21796-072!!
S!R9G25!!RES_0402-4.75K_1%_1/16W_EMPTY_A_NA!!RES!!RES_0402-4.75K,1%,1/16W,EMPTY,G21796-072!!
S!R9G23!!RES_0402-4.75K_1%_1/16W_EMPTY_A_NA!!RES!!RES_0402-4.75K,1%,1/16W,EMPTY,G21796-072!!
S!R3T3!!RES_0402-4.75K_1%_1/16W_EMPTY_A_NA!YES!RES!!RES_0402-4.75K,1%,1/16W,EMPTY,G21796-072!!
S!R8F16!!RES_0402-4.75K_1%_1/16W_EMPTY_A_NA!!RES!!RES_0402-4.75K,1%,1/16W,EMPTY,G21796-072!!
S!R7F6!!RES_0402-4.75K_1%_1/16W_EMPTY_A_NA!YES!RES!!RES_0402-4.75K,1%,1/16W,EMPTY,G21796-072!!
S!R8F25!!DEFAULT_RESISTOR_475.000000OHM_2_1!!RES!!RES_0402-475.0,1%,1/16W,CHIP,G21796-077!!
S!R9A4!!DEFAULT_RESISTOR_475.000000OHM_2_1!!RES!!RES_0402-475.0,1%,1/16W,CHIP,G21796-077!!
S!R8A10!68!DEFAULT_RESISTOR_5110OHM_2_1!!RES!!RES_0402-5.11K,1%,1/16W,CHIP,G21796-140!!
S!R1U29!!DEFAULT_RESISTOR_5110OHM_2_1!!RES!!RES_0402-5.11K,1%,1/16W,CHIP,G21796-140!!
S!R1U26!!DEFAULT_RESISTOR_5110OHM_2_1!!RES!!RES_0402-5.11K,1%,1/16W,CHIP,G21796-140!!
S!R1U47!!DEFAULT_RESISTOR_5110OHM_2_1!!RES!!RES_0402-5.11K,1%,1/16W,CHIP,G21796-140!!
S!R1U32!!DEFAULT_RESISTOR_5110OHM_2_1!!RES!!RES_0402-5.11K,1%,1/16W,CHIP,G21796-140!!
S!R1U39!!DEFAULT_RESISTOR_5110OHM_2_1!!RES!!RES_0402-5.11K,1%,1/16W,CHIP,G21796-140!!
S!R6U16!!!!RES!!RES_0402-51.1,1.0%,1/16W,CHIP,G21796-208!!
S!R4A1!!!!RES!!RES_0402-51.1,1.0%,1/16W,CHIP,G21796-208!!
S!R6U8!!!!RES!!RES_0402-51.1,1.0%,1/16W,CHIP,G21796-208!!
S!R6L7!!!!RES!!RES_0402-51.1,1.0%,1/16W,CHIP,G21796-208!!
S!R7R1!!DEFAULT_RESISTOR_221.000000OHM_2_1!!RES!!RES_0402-51.1,1.0%,1/16W,CHIP,G21796-208!!
S!R6N4!!DEFAULT_RESISTOR_51.000000OHM_2_1!!RES!!RES_0402-51.1,1.0%,1/16W,CHIP,G21796-208!!
S!R9N4!!DEFAULT_RESISTOR_51.000000OHM_2_1!!RES!!RES_0402-51.1,1.0%,1/16W,CHIP,G21796-208!!
S!R7C3!!DEFAULT_RESISTOR_51.000000OHM_2_1!!RES!!RES_0402-51.1,1.0%,1/16W,CHIP,G21796-208!!
S!R2N25!!DEFAULT_RESISTOR_51.100000OHM_2_1!!RES!!RES_0402-51.1,1.0%,1/16W,CHIP,G21796-208!!
S!R7P29!!DEFAULT_RESISTOR_75.000000OHM_2_1!!RES!!RES_0402-51.1,1.0%,1/16W,CHIP,G21796-208!!
S!R8B1!!DEFAULT_RESISTOR_51.100000OHM_2_1!!RES!!RES_0402-51.1,1.0%,1/16W,CHIP,G21796-208!!
S!R9T3!!DEFAULT_RESISTOR_3000OHM_2_1!!RES!!RES_0402-6.19K,1%,1/16W,CHIP,G21796-161!!
S!R1D31!30!DEFAULT_RESISTOR_6190OHM_2_1!!RES!!RES_0402-6.19K,1%,1/16W,CHIP,G21796-161!!
S!R1L21!!!!RES!!RES_0402-64.9,1.0%,1/16W,CHIP,G21796-298!!
S!R7M9!!DEFAULT_RESISTOR_64.900000OHM_2_1!!RES!!RES_0402-64.9,1.0%,1/16W,CHIP,G21796-298!!
S!R3D21!!DEFAULT_RESISTOR_64.900000OHM_2_1!!RES!!RES_0402-64.9,1.0%,1/16W,CHIP,G21796-298!!
S!R3P38!8!DEFAULT_RESISTOR_64.900000OHM_2_1!!RES!!RES_0402-64.9,1.0%,1/16W,CHIP,G21796-298!!
S!R3P29!7!DEFAULT_RESISTOR_64.900000OHM_2_1!!RES!!RES_0402-64.9,1.0%,1/16W,CHIP,G21796-298!!
S!R1T3!!!!RES!!RES_0402-665,1.0%,1/16W,CHIP,G21796-235!!
S!R1T2!!!!RES!!RES_0402-665,1.0%,1/16W,CHIP,G21796-235!!
S!R2T53!!DEFAULT_RESISTOR_3300OHM_2_1!!RES!!RES_0402-665,1.0%,1/16W,CHIP,G21796-235!!
S!R2U39!!DEFAULT_RESISTOR_3300OHM_2_1!!RES!!RES_0402-665,1.0%,1/16W,CHIP,G21796-235!!
S!R2T54!!DEFAULT_RESISTOR_3300OHM_2_1!!RES!!RES_0402-665,1.0%,1/16W,CHIP,G21796-235!!
S!R2U38!!DEFAULT_RESISTOR_3300OHM_2_1!!RES!!RES_0402-665,1.0%,1/16W,CHIP,G21796-235!!
S!R2U11!!DEFAULT_RESISTOR_3300OHM_2_1!!RES!!RES_0402-665,1.0%,1/16W,CHIP,G21796-235!!
S!R2U3!!DEFAULT_RESISTOR_3300OHM_2_1!!RES!!RES_0402-665,1.0%,1/16W,CHIP,G21796-235!!
S!R2N8!!DEFAULT_RESISTOR_3300OHM_2_1!!RES!!RES_0402-665,1.0%,1/16W,CHIP,G21796-235!!
S!R2N5!!DEFAULT_RESISTOR_3300OHM_2_1!!RES!!RES_0402-665,1.0%,1/16W,CHIP,G21796-235!!
S!R4T7!1!DEFAULT_RESISTOR_665.000000OHM_2_1!!RES!!RES_0402-665,1.0%,1/16W,CHIP,G21796-235!!
S!R6U17!!DEFAULT_RESISTOR_665.000000OHM_2_1!!RES!!RES_0402-665,1.0%,1/16W,CHIP,G21796-235!!
S!R7M1!!DEFAULT_RESISTOR_665.000000OHM_2_1!!RES!!RES_0402-665,1.0%,1/16W,CHIP,G21796-235!!
S!R3R5!!DEFAULT_RESISTOR_665.000000OHM_2_1!!RES!!RES_0402-665,1.0%,1/16W,CHIP,G21796-235!!
S!R4T8!2!DEFAULT_RESISTOR_665.000000OHM_2_1!!RES!!RES_0402-665,1.0%,1/16W,CHIP,G21796-235!!
S!R6U18!!DEFAULT_RESISTOR_665.000000OHM_2_1!!RES!!RES_0402-665,1.0%,1/16W,CHIP,G21796-235!!
S!R7M6!!DEFAULT_RESISTOR_665.000000OHM_2_1!!RES!!RES_0402-665,1.0%,1/16W,CHIP,G21796-235!!
S!R3R12!!DEFAULT_RESISTOR_665.000000OHM_2_1!!RES!!RES_0402-665,1.0%,1/16W,CHIP,G21796-235!!
S!R2L8!!DEFAULT_RESISTOR_10.000000OHM_2_1!!RES!!RES_0603-10.0,1%,1/10W,CHIP,G22026-041!!
S!R9P30!11!DEFAULT_RESISTOR_10.000000OHM_2_1!!RES!!RES_0603-10.0,1%,1/10W,CHIP,G22026-041!!
S!R4E13!!DEFAULT_RESISTOR_100.000000OHM_2_1!!RES!!RES_0603-100.0,1%,1/10W,CHIP,G22026-038!!
S!R1E3!!DEFAULT_RESISTOR_100.000000OHM_2_1!!RES!!RES_0603-100.0,1%,1/10W,CHIP,G22026-038!!
S!R7C6!!DEFAULT_RESISTOR_0.01OHM_2_1!!RES!!RES_0603-10M,1.0%,1/10W,CHIP,G22026-112!!
S!R7F10!34!DEFAULT_RESISTOR_121.000000OHM_2_1!!RES!!RES_0603-120.0,1%,1/10W,CHIP,G22026-003!!
S!R7B10!34!DEFAULT_RESISTOR_121.000000OHM_2_1!!RES!!RES_0603-120.0,1%,1/10W,CHIP,G22026-003!!
S!R4G6!34!DEFAULT_RESISTOR_121.000000OHM_2_1!!RES!!RES_0603-120.0,1%,1/10W,CHIP,G22026-003!!
S!R4B2!34!DEFAULT_RESISTOR_121.000000OHM_2_1!!RES!!RES_0603-120.0,1%,1/10W,CHIP,G22026-003!!
S!R3U4!109!DEFAULT_RESISTOR_120.000000OHM_2_1!!RES!!RES_0603-120.0,1%,1/10W,CHIP,G22026-003!!
S!R1G20!30!DEFAULT_RESISTOR_120.000000OHM_2_1!!RES!!RES_0603-120.0,1%,1/10W,CHIP,G22026-003!!
S!R1A1!35!DEFAULT_RESISTOR_120.000000OHM_2_1!!RES!!RES_0603-120.0,1%,1/10W,CHIP,G22026-003!!
S!R4L4!!DEFAULT_RESISTOR_120.000000OHM_2_1!!RES!!RES_0603-120.0,1%,1/10W,CHIP,G22026-003!!
S!R7C19!!RES_0402-0.0_5%_1/16W_EMPTY_G2A_NA!!RES!!RES_0402-0.0,5%,1/16W,CHIP,G21497-005!!
S!R9F33!!DEFAULT_RESISTOR_10.000000OHM_2_1!!RES!!RES_0402-0.0,5%,1/16W,CHIP,G21497-005!!
S!R6D16!!!!RES!!RES_0402-0.0,5%,1/16W,CHIP,G21497-005!!
S!R3D31!!!!RES!!RES_0402-0.0,5%,1/16W,CHIP,G21497-005!!
S!R4A8!!!!RES!!RES_0402-0.0,5%,1/16W,CHIP,G21497-005!!
S!R4A9!!!!RES!!RES_0402-0.0,5%,1/16W,CHIP,G21497-005!!
S!R9M21!!!!RES!!RES_0402-0.0,5%,1/16W,CHIP,G21497-005!!
S!R9M20!!!!RES!!RES_0402-0.0,5%,1/16W,CHIP,G21497-005!!
S!R9B11!!!!RES!!RES_0402-0.0,5%,1/16W,CHIP,G21497-005!!
S!R9B13!!!!RES!!RES_0402-0.0,5%,1/16W,CHIP,G21497-005!!
S!R9F62!!!!RES!!RES_0402-0.0,5%,1/16W,CHIP,G21497-005!!
S!R7E22!!!!RES!!RES_0402-0.0,5%,1/16W,CHIP,G21497-005!!
S!R2T65!!!!RES!!RES_0402-0.0,5%,1/16W,CHIP,G21497-005!!
S!R2T66!!!!RES!!RES_0402-0.0,5%,1/16W,CHIP,G21497-005!!
S!R2T67!!!!RES!!RES_0402-0.0,5%,1/16W,CHIP,G21497-005!!
S!R7D41!!!!RES!!RES_0402-0.0,5%,1/16W,CHIP,G21497-005!!
S!R8F38!!!!RES!!RES_0402-0.0,5%,1/16W,CHIP,G21497-005!!
S!R2T64!!!!RES!!RES_0402-0.0,5%,1/16W,CHIP,G21497-005!!
S!R1T36!!!!RES!!RES_0402-0.0,5%,1/16W,CHIP,G21497-005!!
S!R1T37!!!!RES!!RES_0402-0.0,5%,1/16W,CHIP,G21497-005!!
S!R1U59!!!!RES!!RES_0402-0.0,5%,1/16W,CHIP,G21497-005!!
S!R9G33!!!!RES!!RES_0402-0.0,5%,1/16W,CHIP,G21497-005!!
S!R9G32!!!!RES!!RES_0402-0.0,5%,1/16W,CHIP,G21497-005!!
S!R9G28!!!!RES!!RES_0402-0.0,5%,1/16W,CHIP,G21497-005!!
S!R2U47!!!!RES!!RES_0402-0.0,5%,1/16W,CHIP,G21497-005!!
S!R9G29!!!!RES!!RES_0402-0.0,5%,1/16W,CHIP,G21497-005!!
S!R1U54!!!!RES!!RES_0402-0.0,5%,1/16W,CHIP,G21497-005!!
S!R2U46!!!!RES!!RES_0402-0.0,5%,1/16W,CHIP,G21497-005!!
S!R2T60!!!!RES!!RES_0402-0.0,5%,1/16W,CHIP,G21497-005!!
S!R2T68!!!!RES!!RES_0402-0.0,5%,1/16W,CHIP,G21497-005!!
S!R9G34!!!!RES!!RES_0402-0.0,5%,1/16W,CHIP,G21497-005!!
S!R1U58!!!!RES!!RES_0402-0.0,5%,1/16W,CHIP,G21497-005!!
S!R1U53!!!!RES!!RES_0402-0.0,5%,1/16W,CHIP,G21497-005!!
S!R1U60!!!!RES!!RES_0402-0.0,5%,1/16W,CHIP,G21497-005!!
S!R3F2!!RES_0402-0.0_5%_1/16W_CHIP_G21A_0.0!YES!RES!!RES_0402-0.0,5%,1/16W,CHIP,G21497-005!!
S!R3F4!!RES_0402-0.0_5%_1/16W_CHIP_G21A_0.0!YES!RES!!RES_0402-0.0,5%,1/16W,CHIP,G21497-005!!
S!R6F7!!RES_0402-0.0_5%_1/16W_CHIP_G21A_0.0!YES!RES!!RES_0402-0.0,5%,1/16W,CHIP,G21497-005!!
S!R6F9!!RES_0402-0.0_5%_1/16W_CHIP_G21A_0.0!YES!RES!!RES_0402-0.0,5%,1/16W,CHIP,G21497-005!!
S!R8D43!!!!RES!!RES_0402-0.0,5%,1/16W,CHIP,G21497-005!!
S!R7D36!!!!RES!!RES_0402-0.0,5%,1/16W,CHIP,G21497-005!!
S!R6L6!!RES_0402-0.0_5%_1/16W_EMPTY_G2A_NA!YES!RES!!RES_0402-0.0,5%,1/16W,CHIP,G21497-005!!
S!R1F8!!!!RES!!RES_0402-0.0,5%,1/16W,CHIP,G21497-005!!
S!R1U8!!RES_0402-20.0_1%_1/16W_CHIP_G21A_0.0!!RES!!RES_0402-0.0,5%,1/16W,CHIP,G21497-005!!
S!R1U11!!RES_0402-20.0_1%_1/16W_CHIP_G21A_0.0!!RES!!RES_0402-0.0,5%,1/16W,CHIP,G21497-005!!
S!R1G21!20!RES_0402-20.0_1%_1/16W_CHIP_G21A_0.0!!RES!!RES_0402-0.0,5%,1/16W,CHIP,G21497-005!!
S!R1G19!!RES_0402-20.0_1%_1/16W_CHIP_G21A_0.0!!RES!!RES_0402-0.0,5%,1/16W,CHIP,G21497-005!!
S!R1U51!!!!RES!!RES_0402-0.0,5%,1/16W,CHIP,G21497-005!!
S!R1U3!!!!RES!!RES_0402-0.0,5%,1/16W,CHIP,G21497-005!!
S!R2T2!!DEFAULT_RESISTOR_33.000000OHM_2_1!!RES!!RES_0402-0.0,5%,1/16W,CHIP,G21497-005!!
S!R8G8!!RES_0402-0.0_5%_1/16W_EMPTY_G2A_NA!!RES!!RES_0402-0.0,5%,1/16W,CHIP,G21497-005!!
S!R8G14!!RES_0402-0.0_5%_1/16W_EMPTY_G2A_NA!!RES!!RES_0402-0.0,5%,1/16W,CHIP,G21497-005!!
S!R8G17!!RES_0402-0.0_5%_1/16W_EMPTY_G2A_NA!!RES!!RES_0402-0.0,5%,1/16W,CHIP,G21497-005!!
S!R7G17!!RES_0402-0.0_5%_1/16W_EMPTY_G2A_NA!!RES!!RES_0402-0.0,5%,1/16W,CHIP,G21497-005!!
S!R8G10!!RES_0402-0.0_5%_1/16W_EMPTY_G2A_NA!!RES!!RES_0402-0.0,5%,1/16W,CHIP,G21497-005!!
S!R7D23!!RES_0402-0.0_5%_1/16W_CHIP_G21A_0.0!!RES!!RES_0402-0.0,5%,1/16W,CHIP,G21497-005!!
S!R7C15!!DEFAULT_RESISTOR_33.200000OHM_2_1!!RES!!RES_0402-0.0,5%,1/16W,CHIP,G21497-005!!
S!R8F6!!DEFAULT_RESISTOR_33.200000OHM_2_1!!RES!!RES_0402-0.0,5%,1/16W,CHIP,G21497-005!!
S!R2R12!!DEFAULT_RESISTOR_33.000000OHM_2_1!!RES!!RES_0402-0.0,5%,1/16W,CHIP,G21497-005!!
S!R1M15!!!!RES!!RES_0402-0.0,5%,1/16W,CHIP,G21497-005!!
S!R1M17!!!!RES!!RES_0402-0.0,5%,1/16W,CHIP,G21497-005!!
S!R1M16!!!!RES!!RES_0402-0.0,5%,1/16W,CHIP,G21497-005!!
S!R1M18!!!!RES!!RES_0402-0.0,5%,1/16W,CHIP,G21497-005!!
S!R9N15!!!!RES!!RES_0402-0.0,5%,1/16W,CHIP,G21497-005!!
S!R9N5!!!!RES!!RES_0402-0.0,5%,1/16W,CHIP,G21497-005!!
S!R9N17!!!!RES!!RES_0402-0.0,5%,1/16W,CHIP,G21497-005!!
S!R9N12!!!!RES!!RES_0402-0.0,5%,1/16W,CHIP,G21497-005!!
S!R9N10!!!!RES!!RES_0402-0.0,5%,1/16W,CHIP,G21497-005!!
S!R9N9!!!!RES!!RES_0402-0.0,5%,1/16W,CHIP,G21497-005!!
S!R3P57!!!!RES!!RES_0402-0.0,5%,1/16W,CHIP,G21497-005!!
S!R4D45!!!!RES!!RES_0402-0.0,5%,1/16W,CHIP,G21497-005!!
S!R3U10!!!!RES!!RES_0402-0.0,5%,1/16W,CHIP,G21497-005!!
S!R3U3!!!!RES!!RES_0402-0.0,5%,1/16W,CHIP,G21497-005!!
S!R3L9!!!!RES!!RES_0402-0.0,5%,1/16W,CHIP,G21497-005!!
S!R3L10!!!!RES!!RES_0402-0.0,5%,1/16W,CHIP,G21497-005!!
S!R1G28!!!!RES!!RES_0402-0.0,5%,1/16W,CHIP,G21497-005!!
S!R1G27!!!!RES!!RES_0402-0.0,5%,1/16W,CHIP,G21497-005!!
S!R9M11!!!!RES!!RES_0402-0.0,5%,1/16W,CHIP,G21497-005!!
S!R9M10!!!!RES!!RES_0402-0.0,5%,1/16W,CHIP,G21497-005!!
S!R2L1!!!!RES!!RES_0402-0.0,5%,1/16W,CHIP,G21497-005!!
S!R2L7!!!!RES!!RES_0402-0.0,5%,1/16W,CHIP,G21497-005!!
S!R6P29!!!!RES!!RES_0402-0.0,5%,1/16W,CHIP,G21497-005!!
S!R6P43!!!!RES!!RES_0402-0.0,5%,1/16W,CHIP,G21497-005!!
S!R6P42!!!!RES!!RES_0402-0.0,5%,1/16W,CHIP,G21497-005!!
S!R6P38!!!!RES!!RES_0402-0.0,5%,1/16W,CHIP,G21497-005!!
S!R6P34!!!!RES!!RES_0402-0.0,5%,1/16W,CHIP,G21497-005!!
S!R6P30!!!!RES!!RES_0402-0.0,5%,1/16W,CHIP,G21497-005!!
S!R3P2!!RES_0402-0.0_5%_1/16W_CHIP_G21A_0.0!!RES!!RES_0402-0.0,5%,1/16W,CHIP,G21497-005!!
S!R2P1!!RES_0402-0.0_5%_1/16W_CHIP_G21A_0.0!!RES!!RES_0402-0.0,5%,1/16W,CHIP,G21497-005!!
S!R3P3!!RES_0402-0.0_5%_1/16W_CHIP_G21A_0.0!!RES!!RES_0402-0.0,5%,1/16W,CHIP,G21497-005!!
S!R9F54!!!!RES!!RES_0402-0.0,5%,1/16W,CHIP,G21497-005!!
S!R9F53!!!!RES!!RES_0402-0.0,5%,1/16W,CHIP,G21497-005!!
S!R9F56!!!!RES!!RES_0402-0.0,5%,1/16W,CHIP,G21497-005!!
S!R9F57!!!!RES!!RES_0402-0.0,5%,1/16W,CHIP,G21497-005!!
S!R1M10!!!!RES!!RES_0402-0.0,5%,1/16W,CHIP,G21497-005!!
S!R1M13!!!!RES!!RES_0402-0.0,5%,1/16W,CHIP,G21497-005!!
S!R9T2!!DEFAULT_RESISTOR_0.001OHM_2_1!!RES!!RES_0402-0.0,5%,1/16W,CHIP,G21497-005!!
S!R9R9!!DEFAULT_RESISTOR_0.001OHM_2_1!!RES!!RES_0402-0.0,5%,1/16W,CHIP,G21497-005!!
S!R9R10!!DEFAULT_RESISTOR_0.001OHM_2_1!!RES!!RES_0402-0.0,5%,1/16W,CHIP,G21497-005!!
S!R9T1!!DEFAULT_RESISTOR_0.001OHM_2_1!!RES!!RES_0402-0.0,5%,1/16W,CHIP,G21497-005!!
S!R2R4!!DEFAULT_RESISTOR_0.001OHM_2_1!!RES!!RES_0402-0.0,5%,1/16W,CHIP,G21497-005!!
S!R7G21!!RES_0402-0.0_5%_1/16W_CHIP_G21A_0.0!!RES!!RES_0402-0.0,5%,1/16W,CHIP,G21497-005!!
S!R8G21!!RES_0402-0.0_5%_1/16W_CHIP_G21A_0.0!!RES!!RES_0402-0.0,5%,1/16W,CHIP,G21497-005!!
S!R8G19!!RES_0402-0.0_5%_1/16W_CHIP_G21A_0.0!!RES!!RES_0402-0.0,5%,1/16W,CHIP,G21497-005!!
S!R8G22!!RES_0402-0.0_5%_1/16W_CHIP_G21A_0.0!!RES!!RES_0402-0.0,5%,1/16W,CHIP,G21497-005!!
S!R9E14!!RES_0402-0.0_5%_1/16W_CHIP_G21A_0.0!!RES!!RES_0402-0.0,5%,1/16W,CHIP,G21497-005!!
S!R6P18!!RES_0402-0.0_5%_1/16W_CHIP_G21A_0.0!!RES!!RES_0402-0.0,5%,1/16W,CHIP,G21497-005!!
S!R9N16!!RES_0402-0.0_5%_1/16W_CHIP_G21A_0.0!!RES!!RES_0402-0.0,5%,1/16W,CHIP,G21497-005!!
S!R3P26!!RES_0402-0.0_5%_1/16W_CHIP_G21A_0.0!!RES!!RES_0402-0.0,5%,1/16W,CHIP,G21497-005!!
S!R6P41!!RES_0402-0.0_5%_1/16W_CHIP_G21A_0.0!!RES!!RES_0402-0.0,5%,1/16W,CHIP,G21497-005!!
S!R7F21!!RES_0402-0.0_5%_1/16W_CHIP_G21A_0.0!!RES!!RES_0402-0.0,5%,1/16W,CHIP,G21497-005!!
S!R3M6!!RES_0402-0.0_5%_1/16W_CHIP_G21A_0.0!!RES!!RES_0402-0.0,5%,1/16W,CHIP,G21497-005!!
S!R9U7!!RES_0402-0.0_5%_1/16W_CHIP_G21A_0.0!!RES!!RES_0402-0.0,5%,1/16W,CHIP,G21497-005!!
S!R9M9!!RES_0402-0.0_5%_1/16W_CHIP_G21A_0.0!!RES!!RES_0402-0.0,5%,1/16W,CHIP,G21497-005!!
S!R7F9!!RES_0402-0.0_5%_1/16W_CHIP_G21A_0.0!!RES!!RES_0402-0.0,5%,1/16W,CHIP,G21497-005!!
S!R7B9!!RES_0402-0.0_5%_1/16W_CHIP_G21A_0.0!!RES!!RES_0402-0.0,5%,1/16W,CHIP,G21497-005!!
S!R4G4!!RES_0402-0.0_5%_1/16W_CHIP_G21A_0.0!!RES!!RES_0402-0.0,5%,1/16W,CHIP,G21497-005!!
S!R4B1!!RES_0402-0.0_5%_1/16W_CHIP_G21A_0.0!!RES!!RES_0402-0.0,5%,1/16W,CHIP,G21497-005!!
S!R2L17!!RES_0402-0.0_5%_1/16W_CHIP_G21A_0.0!!RES!!RES_0402-0.0,5%,1/16W,CHIP,G21497-005!!
S!R8F2!!RES_0402-0.0_5%_1/16W_CHIP_G21A_0.0!!RES!!RES_0402-0.0,5%,1/16W,CHIP,G21497-005!!
S!R8E33!!RES_0402-0.0_5%_1/16W_CHIP_G21A_0.0!!RES!!RES_0402-0.0,5%,1/16W,CHIP,G21497-005!!
S!R8C24!!RES_0402-0.0_5%_1/16W_CHIP_G21A_0.0!!RES!!RES_0402-0.0,5%,1/16W,CHIP,G21497-005!!
S!R6U5!12!RES_0402-0.0_5%_1/16W_CHIP_G21A_0.0!YES!RES!!RES_0402-0.0,5%,1/16W,CHIP,G21497-005!!
S!R6L10!!RES_0402-0.0_5%_1/16W_CHIP_G21A_0.0!YES!RES!!RES_0402-0.0,5%,1/16W,CHIP,G21497-005!!
S!R6U6!!RES_0402-0.0_5%_1/16W_CHIP_G21A_0.0!YES!RES!!RES_0402-0.0,5%,1/16W,CHIP,G21497-005!!
S!R8G7!!RES_0402-0.0_5%_1/16W_CHIP_G21A_0.0!!RES!!RES_0402-0.0,5%,1/16W,CHIP,G21497-005!!
S!R8G13!!RES_0402-0.0_5%_1/16W_CHIP_G21A_0.0!!RES!!RES_0402-0.0,5%,1/16W,CHIP,G21497-005!!
S!R8G18!!RES_0402-0.0_5%_1/16W_CHIP_G21A_0.0!!RES!!RES_0402-0.0,5%,1/16W,CHIP,G21497-005!!
S!R7G14!!RES_0402-0.0_5%_1/16W_CHIP_G21A_0.0!!RES!!RES_0402-0.0,5%,1/16W,CHIP,G21497-005!!
S!R7A18!!RES_0402-0.0_5%_1/16W_CHIP_G21A_0.0!!RES!!RES_0402-0.0,5%,1/16W,CHIP,G21497-005!!
S!R7E9!!RES_0402-0.0_5%_1/16W_CHIP_G21A_0.0!!RES!!RES_0402-0.0,5%,1/16W,CHIP,G21497-005!!
S!R1R8!!RES_0402-0.0_5%_1/16W_CHIP_G21A_0.0!!RES!!RES_0402-0.0,5%,1/16W,CHIP,G21497-005!!
S!R7B11!!RES_0402-0.0_5%_1/16W_CHIP_G21A_0.0!!RES!!RES_0402-0.0,5%,1/16W,CHIP,G21497-005!!
S!R4G8!!RES_0402-0.0_5%_1/16W_CHIP_G21A_0.0!!RES!!RES_0402-0.0,5%,1/16W,CHIP,G21497-005!!
S!R4B3!!RES_0402-0.0_5%_1/16W_CHIP_G21A_0.0!!RES!!RES_0402-0.0,5%,1/16W,CHIP,G21497-005!!
S!R7B19!13!RES_0402-0.0_5%_1/16W_CHIP_G21A_0.0!!RES!!RES_0402-0.0,5%,1/16W,CHIP,G21497-005!!
S!R4G24!13!RES_0402-0.0_5%_1/16W_CHIP_G21A_0.0!!RES!!RES_0402-0.0,5%,1/16W,CHIP,G21497-005!!
S!R4B13!13!RES_0402-0.0_5%_1/16W_CHIP_G21A_0.0!!RES!!RES_0402-0.0,5%,1/16W,CHIP,G21497-005!!
S!R9F27!!RES_0402-0.0_5%_1/16W_CHIP_G21A_0.0!!RES!!RES_0402-0.0,5%,1/16W,CHIP,G21497-005!!
S!R9F58!!RES_0402-0.0_5%_1/16W_CHIP_G21A_0.0!!RES!!RES_0402-0.0,5%,1/16W,CHIP,G21497-005!!
S!R9F59!!RES_0402-0.0_5%_1/16W_CHIP_G21A_0.0!!RES!!RES_0402-0.0,5%,1/16W,CHIP,G21497-005!!
S!R7F12!!RES_0402-0.0_5%_1/16W_CHIP_G21A_0.0!!RES!!RES_0402-0.0,5%,1/16W,CHIP,G21497-005!!
S!R8E25!!RES_0402-0.0_5%_1/16W_CHIP_G21A_0.0!!RES!!RES_0402-0.0,5%,1/16W,CHIP,G21497-005!!
S!R2N20!!RES_0402-0.0_5%_1/16W_CHIP_G21A_0.0!!RES!!RES_0402-0.0,5%,1/16W,CHIP,G21497-005!!
S!R2N21!!RES_0402-0.0_5%_1/16W_CHIP_G21A_0.0!!RES!!RES_0402-0.0,5%,1/16W,CHIP,G21497-005!!
S!R7F8!13!RES_0402-0.0_5%_1/16W_CHIP_G21A_0.0!!RES!!RES_0402-0.0,5%,1/16W,CHIP,G21497-005!!
S!R7F35!!RES_0402-0.0_5%_1/16W_CHIP_G21A_0.0!!RES!!RES_0402-0.0,5%,1/16W,CHIP,G21497-005!!
S!R7B20!!RES_0402-0.0_5%_1/16W_CHIP_G21A_0.0!!RES!!RES_0402-0.0,5%,1/16W,CHIP,G21497-005!!
S!R4G25!!RES_0402-0.0_5%_1/16W_CHIP_G21A_0.0!!RES!!RES_0402-0.0,5%,1/16W,CHIP,G21497-005!!
S!R8E35!13!RES_0402-0.0_5%_1/16W_CHIP_G21A_0.0!!RES!!RES_0402-0.0,5%,1/16W,CHIP,G21497-005!!
S!R8E38!!RES_0402-0.0_5%_1/16W_CHIP_G21A_0.0!!RES!!RES_0402-0.0,5%,1/16W,CHIP,G21497-005!!
S!R8F11!!RES_0402-0.0_5%_1/16W_CHIP_G21A_0.0!!RES!!RES_0402-0.0,5%,1/16W,CHIP,G21497-005!!
S!R8D35!!RES_0402-0.0_5%_1/16W_CHIP_G21A_0.0!!RES!!RES_0402-0.0,5%,1/16W,CHIP,G21497-005!!
S!R8E1!!RES_0402-0.0_5%_1/16W_CHIP_G21A_0.0!!RES!!RES_0402-0.0,5%,1/16W,CHIP,G21497-005!!
S!R9G9!!RES_0402-0.0_5%_1/16W_CHIP_G21A_0.0!!RES!!RES_0402-0.0,5%,1/16W,CHIP,G21497-005!!
S!R9G11!!RES_0402-0.0_5%_1/16W_CHIP_G21A_0.0!!RES!!RES_0402-0.0,5%,1/16W,CHIP,G21497-005!!
S!R9G18!!RES_0402-0.0_5%_1/16W_CHIP_G21A_0.0!!RES!!RES_0402-0.0,5%,1/16W,CHIP,G21497-005!!
S!R9G17!!RES_0402-0.0_5%_1/16W_CHIP_G21A_0.0!!RES!!RES_0402-0.0,5%,1/16W,CHIP,G21497-005!!
S!R9G19!!RES_0402-0.0_5%_1/16W_CHIP_G21A_0.0!!RES!!RES_0402-0.0,5%,1/16W,CHIP,G21497-005!!
S!R9G20!!RES_0402-0.0_5%_1/16W_CHIP_G21A_0.0!!RES!!RES_0402-0.0,5%,1/16W,CHIP,G21497-005!!
S!R9G24!!RES_0402-0.0_5%_1/16W_CHIP_G21A_0.0!!RES!!RES_0402-0.0,5%,1/16W,CHIP,G21497-005!!
S!R9G22!!RES_0402-0.0_5%_1/16W_CHIP_G21A_0.0!!RES!!RES_0402-0.0,5%,1/16W,CHIP,G21497-005!!
S!R9A3!!RES_0402-0.0_5%_1/16W_CHIP_G21A_0.0!!RES!!RES_0402-0.0,5%,1/16W,CHIP,G21497-005!!
S!R2U37!!RES_0402-0.0_5%_1/16W_CHIP_G21A_0.0!!RES!!RES_0402-0.0,5%,1/16W,CHIP,G21497-005!!
S!R8E27!!RES_0402-0.0_5%_1/16W_CHIP_G21A_0.0!!RES!!RES_0402-0.0,5%,1/16W,CHIP,G21497-005!!
S!R8E26!!RES_0402-0.0_5%_1/16W_CHIP_G21A_0.0!!RES!!RES_0402-0.0,5%,1/16W,CHIP,G21497-005!!
S!R8E21!!RES_0402-0.0_5%_1/16W_CHIP_G21A_0.0!!RES!!RES_0402-0.0,5%,1/16W,CHIP,G21497-005!!
S!R8E28!!RES_0402-0.0_5%_1/16W_CHIP_G21A_0.0!!RES!!RES_0402-0.0,5%,1/16W,CHIP,G21497-005!!
S!R1M6!!RES_0402-0.0_5%_1/16W_CHIP_G21A_0.0!!RES!!RES_0402-0.0,5%,1/16W,CHIP,G21497-005!!
S!R1M5!!RES_0402-0.0_5%_1/16W_CHIP_G21A_0.0!!RES!!RES_0402-0.0,5%,1/16W,CHIP,G21497-005!!
S!R1L42!!RES_0402-0.0_5%_1/16W_CHIP_G21A_0.0!!RES!!RES_0402-0.0,5%,1/16W,CHIP,G21497-005!!
S!R1L40!!RES_0402-0.0_5%_1/16W_CHIP_G21A_0.0!!RES!!RES_0402-0.0,5%,1/16W,CHIP,G21497-005!!
S!R1M2!!RES_0402-0.0_5%_1/16W_CHIP_G21A_0.0!!RES!!RES_0402-0.0,5%,1/16W,CHIP,G21497-005!!
S!R1M1!!RES_0402-0.0_5%_1/16W_CHIP_G21A_0.0!!RES!!RES_0402-0.0,5%,1/16W,CHIP,G21497-005!!
S!R4A2!!RES_0402-0.0_5%_1/16W_CHIP_G21A_0.0!!RES!!RES_0402-0.0,5%,1/16W,CHIP,G21497-005!!
S!R4G23!20!RES_0402-0.0_5%_1/16W_CHIP_G21A_0.0!!RES!!RES_0402-0.0,5%,1/16W,CHIP,G21497-005!!
S!R4G16!!RES_0402-0.0_5%_1/16W_CHIP_G21A_0.0!!RES!!RES_0402-0.0,5%,1/16W,CHIP,G21497-005!!
S!R4A3!!RES_0402-0.0_5%_1/16W_CHIP_G21A_0.0!!RES!!RES_0402-0.0,5%,1/16W,CHIP,G21497-005!!
S!R9E18!!RES_0402-0.0_5%_1/16W_CHIP_G21A_0.0!!RES!!RES_0402-0.0,5%,1/16W,CHIP,G21497-005!!
S!R3P34!!RES_0402-0.0_5%_1/16W_CHIP_G21A_0.0!!RES!!RES_0402-0.0,5%,1/16W,CHIP,G21497-005!!
S!R3P35!!RES_0402-0.0_5%_1/16W_CHIP_G21A_0.0!!RES!!RES_0402-0.0,5%,1/16W,CHIP,G21497-005!!
S!R9P21!!RES_0402-0.0_5%_1/16W_CHIP_G21A_0.0!!RES!!RES_0402-0.0,5%,1/16W,CHIP,G21497-005!!
S!R2L14!!RES_0402-0.0_5%_1/16W_CHIP_G21A_0.0!!RES!!RES_0402-0.0,5%,1/16W,CHIP,G21497-005!!
S!R1L12!!RES_0402-0.0_5%_1/16W_CHIP_G21A_0.0!!RES!!RES_0402-0.0,5%,1/16W,CHIP,G21497-005!!
S!R2P14!!RES_0402-0.0_5%_1/16W_CHIP_G21A_0.0!!RES!!RES_0402-0.0,5%,1/16W,CHIP,G21497-005!!
S!R3P22!403!RES_0402-0.0_5%_1/16W_CHIP_G21A_0.0!!RES!!RES_0402-0.0,5%,1/16W,CHIP,G21497-005!!
S!R3P1!406!RES_0402-0.0_5%_1/16W_CHIP_G21A_0.0!!RES!!RES_0402-0.0,5%,1/16W,CHIP,G21497-005!!
S!R4D56!380!RES_0402-0.0_5%_1/16W_CHIP_G21A_0.0!!RES!!RES_0402-0.0,5%,1/16W,CHIP,G21497-005!!
S!R3P11!396!RES_0402-0.0_5%_1/16W_CHIP_G21A_0.0!!RES!!RES_0402-0.0,5%,1/16W,CHIP,G21497-005!!
S!R4D54!343!RES_0402-0.0_5%_1/16W_CHIP_G21A_0.0!!RES!!RES_0402-0.0,5%,1/16W,CHIP,G21497-005!!
S!R4D47!354!RES_0402-0.0_5%_1/16W_CHIP_G21A_0.0!!RES!!RES_0402-0.0,5%,1/16W,CHIP,G21497-005!!
S!R8F18!!RES_0402-0.0_5%_1/16W_CHIP_G21A_0.0!!RES!!RES_0402-0.0,5%,1/16W,CHIP,G21497-005!!
S!R8F21!!RES_0402-0.0_5%_1/16W_CHIP_G21A_0.0!!RES!!RES_0402-0.0,5%,1/16W,CHIP,G21497-005!!
S!R1L6!!RES_0402-0.0_5%_1/16W_CHIP_G21A_0.0!!RES!!RES_0402-0.0,5%,1/16W,CHIP,G21497-005!!
S!R9A8!!RES_0402-0.0_5%_1/16W_CHIP_G21A_0.0!!RES!!RES_0402-0.0,5%,1/16W,CHIP,G21497-005!!
S!R4T1!!RES_0402-0.0_5%_1/16W_CHIP_G21A_0.0!!RES!!RES_0402-0.0,5%,1/16W,CHIP,G21497-005!!
S!R8B12!!RES_0402-0.0_5%_1/16W_CHIP_G21A_0.0!!RES!!RES_0402-0.0,5%,1/16W,CHIP,G21497-005!!
S!R8B14!!RES_0402-0.0_5%_1/16W_CHIP_G21A_0.0!!RES!!RES_0402-0.0,5%,1/16W,CHIP,G21497-005!!
S!R8E37!52!RES_0402-0.0_5%_1/16W_CHIP_G21A_0.0!!RES!!RES_0402-0.0,5%,1/16W,CHIP,G21497-005!!
S!R9U10!27!RES_0402-0.0_5%_1/16W_CHIP_G21A_0.0!!RES!!RES_0402-0.0,5%,1/16W,CHIP,G21497-005!!
S!R4F1!!RES_0402-0.0_5%_1/16W_CHIP_G21A_0.0!!RES!!RES_0402-0.0,5%,1/16W,CHIP,G21497-005!!
S!R4B11!!RES_0402-0.0_5%_1/16W_CHIP_G21A_0.0!!RES!!RES_0402-0.0,5%,1/16W,CHIP,G21497-005!!
S!R9T4!!RES_0402-0.0_5%_1/16W_CHIP_G21A_0.0!!RES!!RES_0402-0.0,5%,1/16W,CHIP,G21497-005!!
S!R1B14!!RES_0402-0.0_5%_1/16W_CHIP_G21A_0.0!!RES!!RES_0402-0.0,5%,1/16W,CHIP,G21497-005!!
S!R6U4!!RES_0402-0.0_5%_1/16W_CHIP_G21A_0.0!!RES!!RES_0402-0.0,5%,1/16W,CHIP,G21497-005!!
S!R5U1!6!RES_0402-0.0_5%_1/16W_CHIP_G21A_0.0!!RES!!RES_0402-0.0,5%,1/16W,CHIP,G21497-005!!
S!R9G4!!RES_0402-0.0_5%_1/16W_CHIP_G21A_0.0!!RES!!RES_0402-0.0,5%,1/16W,CHIP,G21497-005!!
S!R6L11!!RES_0402-0.0_5%_1/16W_CHIP_G21A_0.0!!RES!!RES_0402-0.0,5%,1/16W,CHIP,G21497-005!!
S!R5L1!!RES_0402-0.0_5%_1/16W_CHIP_G21A_0.0!!RES!!RES_0402-0.0,5%,1/16W,CHIP,G21497-005!!
S!R8U1!!RES_0402-0.0_5%_1/16W_CHIP_G21A_0.0!!RES!!RES_0402-0.0,5%,1/16W,CHIP,G21497-005!!
S!R8L1!!RES_0402-0.0_5%_1/16W_CHIP_G21A_0.0!!RES!!RES_0402-0.0,5%,1/16W,CHIP,G21497-005!!
S!R6U7!!RES_0402-0.0_5%_1/16W_CHIP_G21A_0.0!!RES!!RES_0402-0.0,5%,1/16W,CHIP,G21497-005!!
S!R6L8!!RES_0402-0.0_5%_1/16W_CHIP_G21A_0.0!!RES!!RES_0402-0.0,5%,1/16W,CHIP,G21497-005!!
S!R3M1!!RES_0402-0.0_5%_1/16W_CHIP_G21A_0.0!!RES!!RES_0402-0.0,5%,1/16W,CHIP,G21497-005!!
S!R7A11!!RES_0402-0.0_5%_1/16W_CHIP_G21A_0.0!!RES!!RES_0402-0.0,5%,1/16W,CHIP,G21497-005!!
S!R7A12!!RES_0402-0.0_5%_1/16W_CHIP_G21A_0.0!!RES!!RES_0402-0.0,5%,1/16W,CHIP,G21497-005!!
S!R1G9!!RES_0402-0.0_5%_1/16W_CHIP_G21A_0.0!!RES!!RES_0402-0.0,5%,1/16W,CHIP,G21497-005!!
S!R1G10!7!RES_0402-0.0_5%_1/16W_CHIP_G21A_0.0!!RES!!RES_0402-0.0,5%,1/16W,CHIP,G21497-005!!
S!R9M3!120!RES_0402-0.0_5%_1/16W_CHIP_G21A_0.0!!RES!!RES_0402-0.0,5%,1/16W,CHIP,G21497-005!!
S!R1B11!113!RES_0402-0.0_5%_1/16W_CHIP_G21A_0.0!!RES!!RES_0402-0.0,5%,1/16W,CHIP,G21497-005!!
S!R1B10!112!RES_0402-0.0_5%_1/16W_CHIP_G21A_0.0!!RES!!RES_0402-0.0,5%,1/16W,CHIP,G21497-005!!
S!R4B14!37!RES_0402-0.0_5%_1/16W_CHIP_G21A_0.0!!RES!!RES_0402-0.0,5%,1/16W,CHIP,G21497-005!!
S!R1E6!!RES_0402-0.0_5%_1/16W_CHIP_G21A_0.0!!RES!!RES_0402-0.0,5%,1/16W,CHIP,G21497-005!!
S!R1E7!2!RES_0402-0.0_5%_1/16W_CHIP_G21A_0.0!!RES!!RES_0402-0.0,5%,1/16W,CHIP,G21497-005!!
S!R3D29!335!RES_0402-0.0_5%_1/16W_CHIP_G21A_0.0!!RES!!RES_0402-0.0,5%,1/16W,CHIP,G21497-005!!
S!R3D30!332!RES_0402-0.0_5%_1/16W_CHIP_G21A_0.0!!RES!!RES_0402-0.0,5%,1/16W,CHIP,G21497-005!!
S!R7E17!46!RES_0402-0.0_5%_1/16W_CHIP_G21A_0.0!YES!RES!!RES_0402-0.0,5%,1/16W,CHIP,G21497-005!!
S!R7E13!35!RES_0402-0.0_5%_1/16W_CHIP_G21A_0.0!!RES!!RES_0402-0.0,5%,1/16W,CHIP,G21497-005!!
S!R2T32!!RES_0402-0.0_5%_1/16W_CHIP_G21A_0.0!!RES!!RES_0402-0.0,5%,1/16W,CHIP,G21497-005!!
S!R2T17!!RES_0402-0.0_5%_1/16W_CHIP_G21A_0.0!!RES!!RES_0402-0.0,5%,1/16W,CHIP,G21497-005!!
S!R2T20!!RES_0402-0.0_5%_1/16W_CHIP_G21A_0.0!!RES!!RES_0402-0.0,5%,1/16W,CHIP,G21497-005!!
S!R2T27!!RES_0402-0.0_5%_1/16W_CHIP_G21A_0.0!!RES!!RES_0402-0.0,5%,1/16W,CHIP,G21497-005!!
S!R9E20!!RES_0402-0.0_5%_1/16W_CHIP_G21A_0.0!!RES!!RES_0402-0.0,5%,1/16W,CHIP,G21497-005!!
S!R1R1!!RES_0402-0.0_5%_1/16W_CHIP_G21A_0.0!!RES!!RES_0402-0.0,5%,1/16W,CHIP,G21497-005!!
S!R3P59!3!RES_0402-0.0_5%_1/16W_CHIP_G21A_0.0!!RES!!RES_0402-0.0,5%,1/16W,CHIP,G21497-005!!
S!R3P58!4!RES_0402-0.0_5%_1/16W_CHIP_G21A_0.0!!RES!!RES_0402-0.0,5%,1/16W,CHIP,G21497-005!!
S!R3P9!14!RES_0402-0.0_5%_1/16W_CHIP_G21A_0.0!!RES!!RES_0402-0.0,5%,1/16W,CHIP,G21497-005!!
S!R3P10!10!RES_0402-0.0_5%_1/16W_CHIP_G21A_0.0!!RES!!RES_0402-0.0,5%,1/16W,CHIP,G21497-005!!
S!R3T13!42!RES_0402-0.0_5%_1/16W_CHIP_G21A_0.0!!RES!!RES_0402-0.0,5%,1/16W,CHIP,G21497-005!!
S!R7G4!99!RES_0402-0.0_5%_1/16W_CHIP_G21A_0.0!!RES!!RES_0402-0.0,5%,1/16W,CHIP,G21497-005!!
S!R4E16!105!RES_0402-0.0_5%_1/16W_CHIP_G21A_0.0!YES!RES!!RES_0402-0.0,5%,1/16W,CHIP,G21497-005!!
S!R4E17!106!RES_0402-0.0_5%_1/16W_CHIP_G21A_0.0!YES!RES!!RES_0402-0.0,5%,1/16W,CHIP,G21497-005!!
S!R4U5!!RES_0402-0.0_5%_1/16W_CHIP_G21A_0.0!!RES!!RES_0402-0.0,5%,1/16W,CHIP,G21497-005!!
S!R4U7!!RES_0402-0.0_5%_1/16W_CHIP_G21A_0.0!!RES!!RES_0402-0.0,5%,1/16W,CHIP,G21497-005!!
S!R7U3!!RES_0402-0.0_5%_1/16W_CHIP_G21A_0.0!!RES!!RES_0402-0.0,5%,1/16W,CHIP,G21497-005!!
S!R7U1!!RES_0402-0.0_5%_1/16W_CHIP_G21A_0.0!!RES!!RES_0402-0.0,5%,1/16W,CHIP,G21497-005!!
S!R7L1!26!RES_0402-0.0_5%_1/16W_CHIP_G21A_0.0!!RES!!RES_0402-0.0,5%,1/16W,CHIP,G21497-005!!
S!R7L3!25!RES_0402-0.0_5%_1/16W_CHIP_G21A_0.0!!RES!!RES_0402-0.0,5%,1/16W,CHIP,G21497-005!!
S!R4L1!!RES_0402-0.0_5%_1/16W_CHIP_G21A_0.0!!RES!!RES_0402-0.0,5%,1/16W,CHIP,G21497-005!!
S!R4L3!!RES_0402-0.0_5%_1/16W_CHIP_G21A_0.0!!RES!!RES_0402-0.0,5%,1/16W,CHIP,G21497-005!!
S!R6B4!4!RES_0402-0.0_5%_1/16W_CHIP_G21A_0.0!!RES!!RES_0402-0.0,5%,1/16W,CHIP,G21497-005!!
S!R6B5!3!RES_0402-0.0_5%_1/16W_CHIP_G21A_0.0!!RES!!RES_0402-0.0,5%,1/16W,CHIP,G21497-005!!
S!R6N11!!RES_0402-0.0_5%_1/16W_CHIP_G21A_0.0!!RES!!RES_0402-0.0,5%,1/16W,CHIP,G21497-005!!
S!R6N12!!RES_0402-0.0_5%_1/16W_CHIP_G21A_0.0!!RES!!RES_0402-0.0,5%,1/16W,CHIP,G21497-005!!
S!R1C3!!RES_0402-0.0_5%_1/16W_CHIP_G21A_0.0!!RES!!RES_0402-0.0,5%,1/16W,CHIP,G21497-005!!
S!R1D24!24!RES_0402-0.0_5%_1/16W_CHIP_G21A_0.0!!RES!!RES_0402-0.0,5%,1/16W,CHIP,G21497-005!!
S!R1D25!25!RES_0402-0.0_5%_1/16W_CHIP_G21A_0.0!!RES!!RES_0402-0.0,5%,1/16W,CHIP,G21497-005!!
S!R9P16!28!RES_0402-0.0_5%_1/16W_CHIP_G21A_0.0!!RES!!RES_0402-0.0,5%,1/16W,CHIP,G21497-005!!
S!R4D26!34!RES_0402-0.0_5%_1/16W_CHIP_G21A_0.0!!RES!!RES_0402-0.0,5%,1/16W,CHIP,G21497-005!!
S!R4D66!26!RES_0402-0.0_5%_1/16W_CHIP_G21A_0.0!!RES!!RES_0402-0.0,5%,1/16W,CHIP,G21497-005!!
S!R4D67!16!RES_0402-0.0_5%_1/16W_CHIP_G21A_0.0!!RES!!RES_0402-0.0,5%,1/16W,CHIP,G21497-005!!
S!R4D50!23!RES_0402-0.0_5%_1/16W_CHIP_G21A_0.0!!RES!!RES_0402-0.0,5%,1/16W,CHIP,G21497-005!!
S!R4D53!22!RES_0402-0.0_5%_1/16W_CHIP_G21A_0.0!!RES!!RES_0402-0.0,5%,1/16W,CHIP,G21497-005!!
S!R1C14!!RES_0402-0.0_5%_1/16W_CHIP_G21A_0.0!!RES!!RES_0402-0.0,5%,1/16W,CHIP,G21497-005!!
S!R1D2!!RES_0402-0.0_5%_1/16W_CHIP_G21A_0.0!!RES!!RES_0402-0.0,5%,1/16W,CHIP,G21497-005!!
S!R1C23!!RES_0402-0.0_5%_1/16W_CHIP_G21A_0.0!!RES!!RES_0402-0.0,5%,1/16W,CHIP,G21497-005!!
S!R1D3!!RES_0402-0.0_5%_1/16W_CHIP_G21A_0.0!!RES!!RES_0402-0.0,5%,1/16W,CHIP,G21497-005!!
S!R1C25!!RES_0402-0.0_5%_1/16W_CHIP_G21A_0.0!!RES!!RES_0402-0.0,5%,1/16W,CHIP,G21497-005!!
S!R1C7!!RES_0402-0.0_5%_1/16W_CHIP_G21A_0.0!!RES!!RES_0402-0.0,5%,1/16W,CHIP,G21497-005!!
S!R1C5!!RES_0402-0.0_5%_1/16W_CHIP_G21A_0.0!!RES!!RES_0402-0.0,5%,1/16W,CHIP,G21497-005!!
S!R4C4!117!RES_0402-0.0_5%_1/16W_CHIP_G21A_0.0!!RES!!RES_0402-0.0,5%,1/16W,CHIP,G21497-005!!
S!R4C2!100!RES_0402-0.0_5%_1/16W_CHIP_G21A_0.0!!RES!!RES_0402-0.0,5%,1/16W,CHIP,G21497-005!!
S!R1C2!!RES_0402-0.0_5%_1/16W_CHIP_G21A_0.0!!RES!!RES_0402-0.0,5%,1/16W,CHIP,G21497-005!!
S!R3B3!!RES_0402-0.0_5%_1/16W_CHIP_G21A_0.0!!RES!!RES_0402-0.0,5%,1/16W,CHIP,G21497-005!!
S!R3B5!!RES_0402-0.0_5%_1/16W_CHIP_G21A_0.0!!RES!!RES_0402-0.0,5%,1/16W,CHIP,G21497-005!!
S!R3D18!!RES_0402-0.0_5%_1/16W_CHIP_G21A_0.0!!RES!!RES_0402-0.0,5%,1/16W,CHIP,G21497-005!!
S!R1D44!!RES_0402-0.0_5%_1/16W_CHIP_G21A_0.0!!RES!!RES_0402-0.0,5%,1/16W,CHIP,G21497-005!!
S!R1D45!!RES_0402-0.0_5%_1/16W_CHIP_G21A_0.0!!RES!!RES_0402-0.0,5%,1/16W,CHIP,G21497-005!!
S!R7D27!12!RES_0402-0.0_5%_1/16W_CHIP_G21A_0.0!!RES!!RES_0402-0.0,5%,1/16W,CHIP,G21497-005!!
S!R7D28!5!RES_0402-0.0_5%_1/16W_CHIP_G21A_0.0!!RES!!RES_0402-0.0,5%,1/16W,CHIP,G21497-005!!
S!R2T40!!RES_0402-0.0_5%_1/16W_CHIP_G21A_0.0!!RES!!RES_0402-0.0,5%,1/16W,CHIP,G21497-005!!
S!R2T44!!RES_0402-0.0_5%_1/16W_CHIP_G21A_0.0!!RES!!RES_0402-0.0,5%,1/16W,CHIP,G21497-005!!
S!R7G2!101!RES_0402-0.0_5%_1/16W_CHIP_G21A_0.0!!RES!!RES_0402-0.0,5%,1/16W,CHIP,G21497-005!!
S!R9F7!!RES_0402-0.0_5%_1/16W_CHIP_G21A_0.0!!RES!!RES_0402-0.0,5%,1/16W,CHIP,G21497-005!!
S!R2U50!!!!RES!!RES_0402-0.0,5%,1/16W,EMPTY,G21497-005!!
S!R7C18!!RES_0402-0.0_5%_1/16W_CHIP_G21A_0.0!!RES!!RES_0402-0.0,5%,1/16W,EMPTY,G21497-005!!
S!R8F37!!!!RES!!RES_0402-0.0,5%,1/16W,EMPTY,G21497-005!!
S!R2T63!!!!RES!!RES_0402-0.0,5%,1/16W,EMPTY,G21497-005!!
S!R1T35!!!!RES!!RES_0402-0.0,5%,1/16W,EMPTY,G21497-005!!
S!R1T38!!!!RES!!RES_0402-0.0,5%,1/16W,EMPTY,G21497-005!!
S!R3N30!!!!RES!!RES_0402-0.0,5%,1/16W,EMPTY,G21497-005!!
S!R9G30!!!!RES!!RES_0402-0.0,5%,1/16W,EMPTY,G21497-005!!
S!R7D35!!!!RES!!RES_0402-0.0,5%,1/16W,EMPTY,G21497-005!!
S!R2U45!!!!RES!!RES_0402-0.0,5%,1/16W,EMPTY,G21497-005!!
S!R2U14!!RES_0402-0.0_5%_1/16W_CHIP_G21A_0.0!!RES!!RES_0402-0.0,5%,1/16W,EMPTY,G21497-005!!
S!R2U15!!RES_0402-0.0_5%_1/16W_CHIP_G21A_0.0!!RES!!RES_0402-0.0,5%,1/16W,EMPTY,G21497-005!!
S!R2U16!!RES_0402-0.0_5%_1/16W_CHIP_G21A_0.0!!RES!!RES_0402-0.0,5%,1/16W,EMPTY,G21497-005!!
S!R2U17!!RES_0402-0.0_5%_1/16W_CHIP_G21A_0.0!!RES!!RES_0402-0.0,5%,1/16W,EMPTY,G21497-005!!
S!R2U18!!RES_0402-0.0_5%_1/16W_CHIP_G21A_0.0!!RES!!RES_0402-0.0,5%,1/16W,EMPTY,G21497-005!!
S!R2U19!!RES_0402-0.0_5%_1/16W_CHIP_G21A_0.0!!RES!!RES_0402-0.0,5%,1/16W,EMPTY,G21497-005!!
S!R2U20!!RES_0402-0.0_5%_1/16W_CHIP_G21A_0.0!!RES!!RES_0402-0.0,5%,1/16W,EMPTY,G21497-005!!
S!R2U21!!RES_0402-0.0_5%_1/16W_CHIP_G21A_0.0!!RES!!RES_0402-0.0,5%,1/16W,EMPTY,G21497-005!!
S!R2U22!!RES_0402-0.0_5%_1/16W_CHIP_G21A_0.0!!RES!!RES_0402-0.0,5%,1/16W,EMPTY,G21497-005!!
S!R2U23!!RES_0402-0.0_5%_1/16W_CHIP_G21A_0.0!!RES!!RES_0402-0.0,5%,1/16W,EMPTY,G21497-005!!
S!R2U24!!RES_0402-0.0_5%_1/16W_CHIP_G21A_0.0!!RES!!RES_0402-0.0,5%,1/16W,EMPTY,G21497-005!!
S!R2U25!!RES_0402-0.0_5%_1/16W_CHIP_G21A_0.0!!RES!!RES_0402-0.0,5%,1/16W,EMPTY,G21497-005!!
S!R2U26!!RES_0402-0.0_5%_1/16W_CHIP_G21A_0.0!!RES!!RES_0402-0.0,5%,1/16W,EMPTY,G21497-005!!
S!R2U27!!RES_0402-0.0_5%_1/16W_CHIP_G21A_0.0!!RES!!RES_0402-0.0,5%,1/16W,EMPTY,G21497-005!!
S!R2U28!!RES_0402-0.0_5%_1/16W_CHIP_G21A_0.0!!RES!!RES_0402-0.0,5%,1/16W,EMPTY,G21497-005!!
S!R2U29!!RES_0402-0.0_5%_1/16W_CHIP_G21A_0.0!!RES!!RES_0402-0.0,5%,1/16W,EMPTY,G21497-005!!
S!R9F60!!!!RES!!RES_0402-0.0,5%,1/16W,EMPTY,G21497-005!!
S!R2T57!!RES_0402-0.0_5%_1/16W_EMPTY_G2A_NA!!RES!!RES_0402-0.0,5%,1/16W,EMPTY,G21497-005!!
S!R2T69!!RES_0402-0.0_5%_1/16W_EMPTY_G2A_NA!!RES!!RES_0402-0.0,5%,1/16W,EMPTY,G21497-005!!
S!R2T61!!RES_0402-0.0_5%_1/16W_EMPTY_G2A_NA!!RES!!RES_0402-0.0,5%,1/16W,EMPTY,G21497-005!!
S!R2T59!!RES_0402-0.0_5%_1/16W_EMPTY_G2A_NA!!RES!!RES_0402-0.0,5%,1/16W,EMPTY,G21497-005!!
S!R2T62!!RES_0402-0.0_5%_1/16W_EMPTY_G2A_NA!!RES!!RES_0402-0.0,5%,1/16W,EMPTY,G21497-005!!
S!R2T71!!RES_0402-0.0_5%_1/16W_EMPTY_G2A_NA!!RES!!RES_0402-0.0,5%,1/16W,EMPTY,G21497-005!!
S!R2T70!!RES_0402-0.0_5%_1/16W_EMPTY_G2A_NA!!RES!!RES_0402-0.0,5%,1/16W,EMPTY,G21497-005!!
S!R2T58!!RES_0402-0.0_5%_1/16W_EMPTY_G2A_NA!!RES!!RES_0402-0.0,5%,1/16W,EMPTY,G21497-005!!
S!R2U51!!RES_0402-0.0_5%_1/16W_EMPTY_G2A_NA!!RES!!RES_0402-0.0,5%,1/16W,EMPTY,G21497-005!!
S!R1U62!!RES_0402-0.0_5%_1/16W_EMPTY_G2A_NA!!RES!!RES_0402-0.0,5%,1/16W,EMPTY,G21497-005!!
S!R1U56!!RES_0402-0.0_5%_1/16W_EMPTY_G2A_NA!!RES!!RES_0402-0.0,5%,1/16W,EMPTY,G21497-005!!
S!R1U55!!RES_0402-0.0_5%_1/16W_EMPTY_G2A_NA!!RES!!RES_0402-0.0,5%,1/16W,EMPTY,G21497-005!!
S!R9G27!!RES_0402-0.0_5%_1/16W_EMPTY_G2A_NA!!RES!!RES_0402-0.0,5%,1/16W,EMPTY,G21497-005!!
S!R1U57!!RES_0402-0.0_5%_1/16W_EMPTY_G2A_NA!!RES!!RES_0402-0.0,5%,1/16W,EMPTY,G21497-005!!
S!R2U49!!RES_0402-0.0_5%_1/16W_EMPTY_G2A_NA!!RES!!RES_0402-0.0,5%,1/16W,EMPTY,G21497-005!!
S!R1U61!!RES_0402-0.0_5%_1/16W_EMPTY_G2A_NA!!RES!!RES_0402-0.0,5%,1/16W,EMPTY,G21497-005!!
S!R7D40!!!!RES!!RES_0402-0.0,5%,1/16W,EMPTY,G21497-005!!
S!R7D38!!!!RES!!RES_0402-0.0,5%,1/16W,EMPTY,G21497-005!!
S!R6F10!!!!RES!!RES_0402-0.0,5%,1/16W,EMPTY,G21497-005!!
S!R6F11!!!!RES!!RES_0402-0.0,5%,1/16W,EMPTY,G21497-005!!
S!R3F5!!!!RES!!RES_0402-0.0,5%,1/16W,EMPTY,G21497-005!!
S!R3F6!!!!RES!!RES_0402-0.0,5%,1/16W,EMPTY,G21497-005!!
S!R7D39!!!!RES!!RES_0402-0.0,5%,1/16W,EMPTY,G21497-005!!
S!R7D37!!!!RES!!RES_0402-0.0,5%,1/16W,EMPTY,G21497-005!!
S!R1C31!!!YES!RES!!RES_0402-0.0,5%,1/16W,EMPTY,G21497-005!!
S!R1C11!!RES_0402-0.0_5%_1/16W_EMPTY_G2A_NA!YES!RES!!RES_0402-0.0,5%,1/16W,EMPTY,G21497-005!!
S!R1C10!!RES_0402-0.0_5%_1/16W_EMPTY_G2A_NA!YES!RES!!RES_0402-0.0,5%,1/16W,EMPTY,G21497-005!!
S!R1C9!!RES_0402-0.0_5%_1/16W_EMPTY_G2A_NA!YES!RES!!RES_0402-0.0,5%,1/16W,EMPTY,G21497-005!!
S!R1F9!!RES_0402-0.0_5%_1/16W_EMPTY_G2A_NA!YES!RES!!RES_0402-0.0,5%,1/16W,EMPTY,G21497-005!!
S!R8C23!!RES_0402-0.0_5%_1/16W_CHIP_G21A_0.0!!RES!!RES_0402-0.0,5%,1/16W,EMPTY,G21497-005!!
S!R9E15!!RES_0402-0.0_5%_1/16W_EMPTY_G2A_NA!!RES!!RES_0402-0.0,5%,1/16W,EMPTY,G21497-005!!
S!R1T24!!RES_0402-0.0_5%_1/16W_EMPTY_G2A_NA!!RES!!RES_0402-0.0,5%,1/16W,EMPTY,G21497-005!!
S!R7C4!!RES_0402-0.0_5%_1/16W_EMPTY_G2A_NA!!RES!!RES_0402-0.0,5%,1/16W,EMPTY,G21497-005!!
S!R7C2!!RES_0402-0.0_5%_1/16W_EMPTY_G2A_NA!!RES!!RES_0402-0.0,5%,1/16W,EMPTY,G21497-005!!
S!R8E11!!RES_0402-0.0_5%_1/16W_EMPTY_G2A_NA!!RES!!RES_0402-0.0,5%,1/16W,EMPTY,G21497-005!!
S!R8G9!!RES_0402-0.0_5%_1/16W_EMPTY_G2A_NA!!RES!!RES_0402-0.0,5%,1/16W,EMPTY,G21497-005!!
S!R9P15!!RES_0402-0.0_5%_1/16W_EMPTY_G2A_NA!!RES!!RES_0402-0.0,5%,1/16W,EMPTY,G21497-005!!
S!R6F6!!RES_0402-0.0_5%_1/16W_EMPTY_G2A_NA!YES!RES!!RES_0402-0.0,5%,1/16W,EMPTY,G21497-005!!
S!R3F1!!RES_0402-0.0_5%_1/16W_EMPTY_G2A_NA!YES!RES!!RES_0402-0.0,5%,1/16W,EMPTY,G21497-005!!
S!R6F8!!RES_0402-0.0_5%_1/16W_EMPTY_G2A_NA!YES!RES!!RES_0402-0.0,5%,1/16W,EMPTY,G21497-005!!
S!R3F3!!RES_0402-0.0_5%_1/16W_EMPTY_G2A_NA!YES!RES!!RES_0402-0.0,5%,1/16W,EMPTY,G21497-005!!
S!R9T8!!RES_0402-0.0_5%_1/16W_EMPTY_G2A_NA!!RES!!RES_0402-0.0,5%,1/16W,EMPTY,G21497-005!!
S!R7G18!!RES_0402-0.0_5%_1/16W_EMPTY_G2A_NA!!RES!!RES_0402-0.0,5%,1/16W,EMPTY,G21497-005!!
S!R8G11!!RES_0402-0.0_5%_1/16W_EMPTY_G2A_NA!!RES!!RES_0402-0.0,5%,1/16W,EMPTY,G21497-005!!
S!R8G16!!RES_0402-0.0_5%_1/16W_EMPTY_G2A_NA!!RES!!RES_0402-0.0,5%,1/16W,EMPTY,G21497-005!!
S!R7G15!!RES_0402-0.0_5%_1/16W_EMPTY_G2A_NA!!RES!!RES_0402-0.0,5%,1/16W,EMPTY,G21497-005!!
S!R2P12!!RES_0402-0.0_5%_1/16W_EMPTY_G2A_NA!!RES!!RES_0402-0.0,5%,1/16W,EMPTY,G21497-005!!
S!R7G19!!RES_0402-0.0_5%_1/16W_EMPTY_G2A_NA!!RES!!RES_0402-0.0,5%,1/16W,EMPTY,G21497-005!!
S!R8G12!!RES_0402-0.0_5%_1/16W_EMPTY_G2A_NA!!RES!!RES_0402-0.0,5%,1/16W,EMPTY,G21497-005!!
S!R8G15!!RES_0402-0.0_5%_1/16W_EMPTY_G2A_NA!!RES!!RES_0402-0.0,5%,1/16W,EMPTY,G21497-005!!
S!R7G16!!RES_0402-0.0_5%_1/16W_EMPTY_G2A_NA!!RES!!RES_0402-0.0,5%,1/16W,EMPTY,G21497-005!!
S!R8E29!!RES_0402-0.0_5%_1/16W_EMPTY_G2A_NA!!RES!!RES_0402-0.0,5%,1/16W,EMPTY,G21497-005!!
S!R9G5!!RES_0402-0.0_5%_1/16W_EMPTY_G2A_NA!!RES!!RES_0402-0.0,5%,1/16W,EMPTY,G21497-005!!
S!R9G6!!RES_0402-0.0_5%_1/16W_EMPTY_G2A_NA!!RES!!RES_0402-0.0,5%,1/16W,EMPTY,G21497-005!!
S!R1T15!!RES_0402-0.0_5%_1/16W_EMPTY_G2A_NA!!RES!!RES_0402-0.0,5%,1/16W,EMPTY,G21497-005!!
S!R1T23!!RES_0402-0.0_5%_1/16W_EMPTY_G2A_NA!!RES!!RES_0402-0.0,5%,1/16W,EMPTY,G21497-005!!
S!R9F24!!RES_0402-0.0_5%_1/16W_EMPTY_G2A_NA!!RES!!RES_0402-0.0,5%,1/16W,EMPTY,G21497-005!!
S!R9F26!!RES_0402-0.0_5%_1/16W_EMPTY_G2A_NA!!RES!!RES_0402-0.0,5%,1/16W,EMPTY,G21497-005!!
S!R4T2!!RES_0402-0.0_5%_1/16W_EMPTY_G2A_NA!!RES!!RES_0402-0.0,5%,1/16W,EMPTY,G21497-005!!
S!R3L4!18!DEFAULT_RESISTOR_1.000000OHM_2_1!!RES!!RES_0402-1.0,1%,1/16W,CHIP,G21796-090!!
S!R3L1!!DEFAULT_RESISTOR_1.000000OHM_2_1!!RES!!RES_0402-1.0,1%,1/16W,CHIP,G21796-090!!
S!R3N7!394!DEFAULT_RESISTOR_1.000000OHM_2_1!!RES!!RES_0402-1.0,1%,1/16W,CHIP,G21796-090!!
S!R6R5!329!DEFAULT_RESISTOR_1.000000OHM_2_1!!RES!!RES_0402-1.0,1%,1/16W,CHIP,G21796-090!!
S!R6P19!!DEFAULT_RESISTOR_1.000000OHM_2_1!!RES!!RES_0402-1.0,1%,1/16W,CHIP,G21796-090!!
S!R6P10!!DEFAULT_RESISTOR_1.000000OHM_2_1!!RES!!RES_0402-1.0,1%,1/16W,CHIP,G21796-090!!
S!R9P32!!DEFAULT_RESISTOR_1.000000OHM_2_1!!RES!!RES_0402-1.0,1%,1/16W,CHIP,G21796-090!!
S!R6R6!50!DEFAULT_RESISTOR_1.000000OHM_2_1!!RES!!RES_0402-1.0,1%,1/16W,CHIP,G21796-090!!
S!R6R2!36!DEFAULT_RESISTOR_1.000000OHM_2_1!!RES!!RES_0402-1.0,1%,1/16W,CHIP,G21796-090!!
S!R6P47!64!DEFAULT_RESISTOR_1.000000OHM_2_1!!RES!!RES_0402-1.0,1%,1/16W,CHIP,G21796-090!!
S!R3U6!51!DEFAULT_RESISTOR_1.000000OHM_2_1!!RES!!RES_0402-1.0,1%,1/16W,CHIP,G21796-090!!
S!R3U9!17!DEFAULT_RESISTOR_1.000000OHM_2_1!!RES!!RES_0402-1.0,1%,1/16W,CHIP,G21796-090!!
S!R3L6!23!DEFAULT_RESISTOR_1.000000OHM_2_1!!RES!!RES_0402-1.0,1%,1/16W,CHIP,G21796-090!!
S!R3L8!11!DEFAULT_RESISTOR_1.000000OHM_2_1!!RES!!RES_0402-1.0,1%,1/16W,CHIP,G21796-090!!
S!R9L9!112!DEFAULT_RESISTOR_1.000000OHM_2_1!!RES!!RES_0402-1.0,1%,1/16W,CHIP,G21796-090!!
S!R9L4!90!DEFAULT_RESISTOR_1.000000OHM_2_1!!RES!!RES_0402-1.0,1%,1/16W,CHIP,G21796-090!!
S!R6N3!78!DEFAULT_RESISTOR_1.000000OHM_2_1!!RES!!RES_0402-1.0,1%,1/16W,CHIP,G21796-090!!
S!R9U1!14!DEFAULT_RESISTOR_1.000000OHM_2_1!!RES!!RES_0402-1.0,1%,1/16W,CHIP,G21796-090!!
S!R9U12!19!DEFAULT_RESISTOR_1.000000OHM_2_1!!RES!!RES_0402-1.0,1%,1/16W,CHIP,G21796-090!!
S!R9R11!!DEFAULT_RESISTOR_1.000000OHM_2_1!!RES!!RES_0402-1.0,1%,1/16W,CHIP,G21796-090!!
S!R9R2!7!DEFAULT_RESISTOR_1.000000OHM_2_1!!RES!!RES_0402-1.0,1%,1/16W,CHIP,G21796-090!!
S!R9P22!4!DEFAULT_RESISTOR_1.000000OHM_2_1!!RES!!RES_0402-1.0,1%,1/16W,CHIP,G21796-090!!
S!R9P8!!DEFAULT_RESISTOR_1.000000OHM_2_1!!RES!!RES_0402-1.0,1%,1/16W,CHIP,G21796-090!!
S!R9N3!!DEFAULT_RESISTOR_1.000000OHM_2_1!!RES!!RES_0402-1.0,1%,1/16W,CHIP,G21796-090!!
S!R3P56!!!!RES!!RES_0402-1.00K,1%,1/16W,CHIP,G21796-026!!
S!R1C36!!!!RES!!RES_0402-1.00K,1%,1/16W,CHIP,G21796-026!!
S!R6N14!!!!RES!!RES_0402-1.00K,1%,1/16W,CHIP,G21796-026!!
S!R6N13!!!!RES!!RES_0402-1.00K,1%,1/16W,CHIP,G21796-026!!
S!R6N15!!!!RES!!RES_0402-1.00K,1%,1/16W,CHIP,G21796-026!!
S!R1C33!!!!RES!!RES_0402-1.00K,1%,1/16W,CHIP,G21796-026!!
S!R1C32!!!!RES!!RES_0402-1.00K,1%,1/16W,CHIP,G21796-026!!
S!R7E20!!!!RES!!RES_0402-1.00K,1%,1/16W,CHIP,G21796-026!!
S!R1M20!!!!RES!!RES_0402-1.00K,1%,1/16W,CHIP,G21796-026!!
S!R1M19!!!!RES!!RES_0402-1.00K,1%,1/16W,CHIP,G21796-026!!
S!R9B12!!!!RES!!RES_0402-1.00K,1%,1/16W,CHIP,G21796-026!!
S!R1M21!!!!RES!!RES_0402-1.00K,1%,1/16W,CHIP,G21796-026!!
S!R9B9!!!!RES!!RES_0402-1.00K,1%,1/16W,CHIP,G21796-026!!
S!R9B14!!!!RES!!RES_0402-1.00K,1%,1/16W,CHIP,G21796-026!!
S!R2T5!!DEFAULT_RESISTOR_1000.000000OHM_2_1!!RES!!RES_0402-1.00K,1%,1/16W,CHIP,G21796-026!!
S!R2T7!!DEFAULT_RESISTOR_1000.000000OHM_2_1!!RES!!RES_0402-1.00K,1%,1/16W,CHIP,G21796-026!!
S!R8E2!!DEFAULT_RESISTOR_1000.000000OHM_2_1!!RES!!RES_0402-1.00K,1%,1/16W,CHIP,G21796-026!!
S!R4R1!!DEFAULT_RESISTOR_33.200000OHM_2_1!!RES!!RES_0402-1.00K,1%,1/16W,CHIP,G21796-026!!
S!R9F51!!RES_0402-4.75K_1%_1/16W_CHIP_GA_4.75K!!RES!!RES_0402-1.00K,1%,1/16W,CHIP,G21796-026!!
S!R9F50!!RES_0402-4.75K_1%_1/16W_CHIP_GA_4.75K!!RES!!RES_0402-1.00K,1%,1/16W,CHIP,G21796-026!!
S!R7D2!!DEFAULT_RESISTOR_10000OHM_2_1!!RES!!RES_0402-1.00K,1%,1/16W,CHIP,G21796-026!!
S!R7D7!!DEFAULT_RESISTOR_10000OHM_2_1!!RES!!RES_0402-1.00K,1%,1/16W,CHIP,G21796-026!!
S!R3R15!!DEFAULT_RESISTOR_1000.000000OHM_2_1!!RES!!RES_0402-1.00K,1%,1/16W,CHIP,G21796-026!!
S!R6P16!!DEFAULT_RESISTOR_1000.000000OHM_2_1!!RES!!RES_0402-1.00K,1%,1/16W,CHIP,G21796-026!!
S!R9N14!!DEFAULT_RESISTOR_1000.000000OHM_2_1!!RES!!RES_0402-1.00K,1%,1/16W,CHIP,G21796-026!!
S!R6P21!!DEFAULT_RESISTOR_10000OHM_2_1!!RES!!RES_0402-1.00K,1%,1/16W,CHIP,G21796-026!!
S!R6P20!!DEFAULT_RESISTOR_10000OHM_2_1!!RES!!RES_0402-1.00K,1%,1/16W,CHIP,G21796-026!!
S!R7D18!!DEFAULT_RESISTOR_1000.000000OHM_2_1!!RES!!RES_0402-1.00K,1%,1/16W,CHIP,G21796-026!!
S!R3R2!!DEFAULT_RESISTOR_1000.000000OHM_2_1!!RES!!RES_0402-1.00K,1%,1/16W,CHIP,G21796-026!!
S!R3P7!!DEFAULT_RESISTOR_1000.000000OHM_2_1!!RES!!RES_0402-1.00K,1%,1/16W,CHIP,G21796-026!!
S!R3P5!!DEFAULT_RESISTOR_1000.000000OHM_2_1!!RES!!RES_0402-1.00K,1%,1/16W,CHIP,G21796-026!!
S!R3P6!!DEFAULT_RESISTOR_1000.000000OHM_2_1!!RES!!RES_0402-1.00K,1%,1/16W,CHIP,G21796-026!!
S!R3N15!!DEFAULT_RESISTOR_1000.000000OHM_2_1!!RES!!RES_0402-1.00K,1%,1/16W,CHIP,G21796-026!!
S!R3N16!!DEFAULT_RESISTOR_1000.000000OHM_2_1!!RES!!RES_0402-1.00K,1%,1/16W,CHIP,G21796-026!!
S!R3P8!!DEFAULT_RESISTOR_1000.000000OHM_2_1!!RES!!RES_0402-1.00K,1%,1/16W,CHIP,G21796-026!!
S!R8D28!!DEFAULT_RESISTOR_1000.000000OHM_2_1!!RES!!RES_0402-1.00K,1%,1/16W,CHIP,G21796-026!!
S!R1E9!4!DEFAULT_RESISTOR_10000OHM_2_1!!RES!!RES_0402-1.00K,1%,1/16W,CHIP,G21796-026!!
S!R7G27!!DEFAULT_RESISTOR_1000.000000OHM_2_1!!RES!!RES_0402-1.00K,1%,1/16W,CHIP,G21796-026!!
S!R7B17!21!DEFAULT_RESISTOR_1000.000000OHM_2_1!!RES!!RES_0402-1.00K,1%,1/16W,CHIP,G21796-026!!
S!R4G14!21!DEFAULT_RESISTOR_1000.000000OHM_2_1!!RES!!RES_0402-1.00K,1%,1/16W,CHIP,G21796-026!!
S!R4B10!21!DEFAULT_RESISTOR_1000.000000OHM_2_1!!RES!!RES_0402-1.00K,1%,1/16W,CHIP,G21796-026!!
S!R8C4!!DEFAULT_RESISTOR_1000.000000OHM_2_1!!RES!!RES_0402-1.00K,1%,1/16W,CHIP,G21796-026!!
S!R8B23!!DEFAULT_RESISTOR_1000.000000OHM_2_1!!RES!!RES_0402-1.00K,1%,1/16W,CHIP,G21796-026!!
S!R8B30!!DEFAULT_RESISTOR_1000.000000OHM_2_1!!RES!!RES_0402-1.00K,1%,1/16W,CHIP,G21796-026!!
S!R2N18!!DEFAULT_RESISTOR_1000.000000OHM_2_1!!RES!!RES_0402-1.00K,1%,1/16W,CHIP,G21796-026!!
S!R2M4!!DEFAULT_RESISTOR_1000.000000OHM_2_1!!RES!!RES_0402-1.00K,1%,1/16W,CHIP,G21796-026!!
S!R7F19!21!DEFAULT_RESISTOR_1000.000000OHM_2_1!!RES!!RES_0402-1.00K,1%,1/16W,CHIP,G21796-026!!
S!R8F5!21!DEFAULT_RESISTOR_1000.000000OHM_2_1!!RES!!RES_0402-1.00K,1%,1/16W,CHIP,G21796-026!!
S!R8D21!!DEFAULT_RESISTOR_1000.000000OHM_2_1!!RES!!RES_0402-1.00K,1%,1/16W,CHIP,G21796-026!!
S!R2L18!!DEFAULT_RESISTOR_1000.000000OHM_2_1!!RES!!RES_0402-1.00K,1%,1/16W,CHIP,G21796-026!!
S!R2L22!!DEFAULT_RESISTOR_1000.000000OHM_2_1!!RES!!RES_0402-1.00K,1%,1/16W,CHIP,G21796-026!!
S!R1U64!!DEFAULT_RESISTOR_1000.000000OHM_2_1!!RES!!RES_0402-1.00K,1%,1/16W,CHIP,G21796-026!!
S!R6T5!!DEFAULT_RESISTOR_51.100000OHM_2_1!!RES!!RES_0402-1.00K,1%,1/16W,CHIP,G21796-026!!
S!R7G28!!DEFAULT_RESISTOR_1000.000000OHM_2_1!!RES!!RES_0402-1.00K,1%,1/16W,CHIP,G21796-026!!
S!R1U33!!DEFAULT_RESISTOR_1020OHM_2_1!!RES!!RES_0402-1.00K,1%,1/16W,CHIP,G21796-026!!
S!R1L36!!DEFAULT_RESISTOR_1000.000000OHM_2_1!!RES!!RES_0402-1.00K,1%,1/16W,CHIP,G21796-026!!
S!R1L38!!DEFAULT_RESISTOR_1000.000000OHM_2_1!!RES!!RES_0402-1.00K,1%,1/16W,CHIP,G21796-026!!
S!R1L5!!DEFAULT_RESISTOR_1000.000000OHM_2_1!!RES!!RES_0402-1.00K,1%,1/16W,CHIP,G21796-026!!
S!R1L3!!DEFAULT_RESISTOR_1000.000000OHM_2_1!!RES!!RES_0402-1.00K,1%,1/16W,CHIP,G21796-026!!
S!R2R5!!DEFAULT_RESISTOR_1000.000000OHM_2_1!!RES!!RES_0402-1.00K,1%,1/16W,CHIP,G21796-026!!
S!R8B2!!DEFAULT_RESISTOR_51.100000OHM_2_1!!RES!!RES_0402-1.00K,1%,1/16W,CHIP,G21796-026!!
S!R3M10!!DEFAULT_RESISTOR_51.100000OHM_2_1!!RES!!RES_0402-1.00K,1%,1/16W,CHIP,G21796-026!!
S!R3P18!408!DEFAULT_RESISTOR_1000.000000OHM_2_1!!RES!!RES_0402-1.00K,1%,1/16W,CHIP,G21796-026!!
S!R4D49!!DEFAULT_RESISTOR_1000.000000OHM_2_1!!RES!!RES_0402-1.00K,1%,1/16W,CHIP,G21796-026!!
S!R8A5!!DEFAULT_RESISTOR_1000.000000OHM_2_1!!RES!!RES_0402-1.00K,1%,1/16W,CHIP,G21796-026!!
S!R7B4!!DEFAULT_RESISTOR_1000.000000OHM_2_1!!RES!!RES_0402-1.00K,1%,1/16W,CHIP,G21796-026!!
S!R1G11!!DEFAULT_RESISTOR_1000.000000OHM_2_1!!RES!!RES_0402-1.00K,1%,1/16W,CHIP,G21796-026!!
S!R1B1!!DEFAULT_RESISTOR_1000.000000OHM_2_1!!RES!!RES_0402-1.00K,1%,1/16W,CHIP,G21796-026!!
S!R7F27!!DEFAULT_RESISTOR_1000.000000OHM_2_1!!RES!!RES_0402-1.00K,1%,1/16W,CHIP,G21796-026!!
S!R8A6!!DEFAULT_RESISTOR_1000.000000OHM_2_1!!RES!!RES_0402-1.00K,1%,1/16W,CHIP,G21796-026!!
S!R1U15!!DEFAULT_RESISTOR_1000.000000OHM_2_1!!RES!!RES_0402-1.00K,1%,1/16W,CHIP,G21796-026!!
S!R1T11!!DEFAULT_RESISTOR_1000.000000OHM_2_1!!RES!!RES_0402-1.00K,1%,1/16W,CHIP,G21796-026!!
S!R1U16!!DEFAULT_RESISTOR_1000.000000OHM_2_1!!RES!!RES_0402-1.00K,1%,1/16W,CHIP,G21796-026!!
S!R1T12!!DEFAULT_RESISTOR_1000.000000OHM_2_1!!RES!!RES_0402-1.00K,1%,1/16W,CHIP,G21796-026!!
S!R1U30!!DEFAULT_RESISTOR_1000.000000OHM_2_1!!RES!!RES_0402-1.00K,1%,1/16W,CHIP,G21796-026!!
S!R3P25!400!DEFAULT_RESISTOR_1000.000000OHM_2_1!!RES!!RES_0402-1.00K,1%,1/16W,CHIP,G21796-026!!
S!R4D42!350!DEFAULT_RESISTOR_1000.000000OHM_2_1!!RES!!RES_0402-1.00K,1%,1/16W,CHIP,G21796-026!!
S!R3P32!12!DEFAULT_RESISTOR_1000.000000OHM_2_1!!RES!!RES_0402-1.00K,1%,1/16W,CHIP,G21796-026!!
S!R4C9!!DEFAULT_RESISTOR_1000.000000OHM_2_1!!RES!!RES_0402-1.00K,1%,1/16W,CHIP,G21796-026!!
S!R9B6!4!DEFAULT_RESISTOR_1000.000000OHM_2_1!!RES!!RES_0402-1.00K,1%,1/16W,CHIP,G21796-026!!
S!R8D27!!DEFAULT_RESISTOR_1000.000000OHM_2_1!!RES!!RES_0402-1.00K,1%,1/16W,CHIP,G21796-026!!
S!R9B8!3!DEFAULT_RESISTOR_1000.000000OHM_2_1!!RES!!RES_0402-1.00K,1%,1/16W,CHIP,G21796-026!!
S!R8C18!!DEFAULT_RESISTOR_1000.000000OHM_2_1!!RES!!RES_0402-1.00K,1%,1/16W,CHIP,G21796-026!!
S!R2T1!!DEFAULT_RESISTOR_1000.000000OHM_2_1!!RES!!RES_0402-1.00K,1%,1/16W,CHIP,G21796-026!!
S!R7D1!!DEFAULT_RESISTOR_1000.000000OHM_2_1!!RES!!RES_0402-1.00K,1%,1/16W,CHIP,G21796-026!!
S!R1E10!7!DEFAULT_RESISTOR_1000.000000OHM_2_1!!RES!!RES_0402-1.00K,1%,1/16W,CHIP,G21796-026!!
S!R7B5!!DEFAULT_RESISTOR_1000.000000OHM_2_1!!RES!!RES_0402-1.00K,1%,1/16W,CHIP,G21796-026!!
S!R1G16!23!DEFAULT_RESISTOR_1000.000000OHM_2_1!!RES!!RES_0402-1.00K,1%,1/16W,CHIP,G21796-026!!
S!R1B2!109!DEFAULT_RESISTOR_1000.000000OHM_2_1!!RES!!RES_0402-1.00K,1%,1/16W,CHIP,G21796-026!!
S!R7E12!21!DEFAULT_RESISTOR_1000.000000OHM_2_1!!RES!!RES_0402-1.00K,1%,1/16W,CHIP,G21796-026!!
S!R2T50!!DEFAULT_RESISTOR_1000.000000OHM_2_1!!RES!!RES_0402-1.00K,1%,1/16W,CHIP,G21796-026!!
S!R2T25!!DEFAULT_RESISTOR_1000.000000OHM_2_1!!RES!!RES_0402-1.00K,1%,1/16W,CHIP,G21796-026!!
S!R1G2!!DEFAULT_RESISTOR_1000.000000OHM_2_1!!RES!!RES_0402-1.00K,1%,1/16W,CHIP,G21796-026!!
S!R1G15!4!DEFAULT_RESISTOR_1000.000000OHM_2_1!!RES!!RES_0402-1.00K,1%,1/16W,CHIP,G21796-026!!
S!R9L7!!DEFAULT_RESISTOR_1000.000000OHM_2_1!!RES!!RES_0402-1.00K,1%,1/16W,CHIP,G21796-026!!
S!R9L2!!DEFAULT_RESISTOR_1000.000000OHM_2_1!!RES!!RES_0402-1.00K,1%,1/16W,CHIP,G21796-026!!
S!R1G3!!DEFAULT_RESISTOR_1000.000000OHM_2_1!!RES!!RES_0402-1.00K,1%,1/16W,CHIP,G21796-026!!
S!R1G17!1!DEFAULT_RESISTOR_1000.000000OHM_2_1!!RES!!RES_0402-1.00K,1%,1/16W,CHIP,G21796-026!!
S!R9L6!!DEFAULT_RESISTOR_1000.000000OHM_2_1!!RES!!RES_0402-1.00K,1%,1/16W,CHIP,G21796-026!!
S!R9L1!!DEFAULT_RESISTOR_1000.000000OHM_2_1!!RES!!RES_0402-1.00K,1%,1/16W,CHIP,G21796-026!!
S!R6L13!!DEFAULT_RESISTOR_1000.000000OHM_2_1!!RES!!RES_0402-1.00K,1%,1/16W,CHIP,G21796-026!!
S!R4G2!!DEFAULT_RESISTOR_1000.000000OHM_2_1!!RES!!RES_0402-1.00K,1%,1/16W,CHIP,G21796-026!!
S!R4G21!!DEFAULT_RESISTOR_1000.000000OHM_2_1!!RES!!RES_0402-1.00K,1%,1/16W,CHIP,G21796-026!!
S!R6L2!!DEFAULT_RESISTOR_1000.000000OHM_2_1!!RES!!RES_0402-1.00K,1%,1/16W,CHIP,G21796-026!!
S!R6L12!!DEFAULT_RESISTOR_1000.000000OHM_2_1!!RES!!RES_0402-1.00K,1%,1/16W,CHIP,G21796-026!!
S!R4G3!!DEFAULT_RESISTOR_1000.000000OHM_2_1!!RES!!RES_0402-1.00K,1%,1/16W,CHIP,G21796-026!!
S!R4G22!!DEFAULT_RESISTOR_1000.000000OHM_2_1!!RES!!RES_0402-1.00K,1%,1/16W,CHIP,G21796-026!!
S!R6L1!!DEFAULT_RESISTOR_1000.000000OHM_2_1!!RES!!RES_0402-1.00K,1%,1/16W,CHIP,G21796-026!!
S!R3P36!11!DEFAULT_RESISTOR_1000.000000OHM_2_1!!RES!!RES_0402-1.00K,1%,1/16W,CHIP,G21796-026!!
S!R4C8!!DEFAULT_RESISTOR_1000.000000OHM_2_1!!RES!!RES_0402-1.00K,1%,1/16W,CHIP,G21796-026!!
S!R9A17!!DEFAULT_RESISTOR_100.000000OHM_2_1!!RES!!RES_0402-1.00K,1%,1/16W,CHIP,G21796-026!!
S!R9A15!!DEFAULT_RESISTOR_1000.000000OHM_2_1!!RES!!RES_0402-1.00K,1%,1/16W,CHIP,G21796-026!!
S!R2P2!!DEFAULT_RESISTOR_1000.000000OHM_2_1!!RES!!RES_0402-1.00K,1%,1/16W,CHIP,G21796-026!!
S!R4F4!!DEFAULT_RESISTOR_1000.000000OHM_2_1!!RES!!RES_0402-1.00K,1%,1/16W,CHIP,G21796-026!!
S!R9M1!!DEFAULT_RESISTOR_1000.000000OHM_2_1!!RES!!RES_0402-1.00K,1%,1/16W,CHIP,G21796-026!!
S!R1F5!!DEFAULT_RESISTOR_1000.000000OHM_2_1!!RES!!RES_0402-1.00K,1%,1/16W,CHIP,G21796-026!!
S!R6M1!!DEFAULT_RESISTOR_1000.000000OHM_2_1!!RES!!RES_0402-1.00K,1%,1/16W,CHIP,G21796-026!!
S!R1L13!!DEFAULT_RESISTOR_1000.000000OHM_2_1!!RES!!RES_0402-1.00K,1%,1/16W,CHIP,G21796-026!!
S!R9A14!!DEFAULT_RESISTOR_1000.000000OHM_2_1!!RES!!RES_0402-1.00K,1%,1/16W,CHIP,G21796-026!!
S!R1L23!!DEFAULT_RESISTOR_1000.000000OHM_2_1!!RES!!RES_0402-1.00K,1%,1/16W,CHIP,G21796-026!!
S!R2U43!!DEFAULT_RESISTOR_1000.000000OHM_2_1!!RES!!RES_0402-1.00K,1%,1/16W,CHIP,G21796-026!!
S!R1T30!!DEFAULT_RESISTOR_1000.000000OHM_2_1!!RES!!RES_0402-1.00K,1%,1/16W,CHIP,G21796-026!!
S!R1T29!!DEFAULT_RESISTOR_1000.000000OHM_2_1!!RES!!RES_0402-1.00K,1%,1/16W,CHIP,G21796-026!!
S!R7G29!!DEFAULT_RESISTOR_1000.000000OHM_2_1!!RES!!RES_0402-1.00K,1%,1/16W,CHIP,G21796-026!!
S!R7G31!!DEFAULT_RESISTOR_1000.000000OHM_2_1!!RES!!RES_0402-1.00K,1%,1/16W,CHIP,G21796-026!!
S!R1U63!!DEFAULT_RESISTOR_1000.000000OHM_2_1!!RES!!RES_0402-1.00K,1%,1/16W,CHIP,G21796-026!!
S!R1F6!!DEFAULT_RESISTOR_1000.000000OHM_2_1!!RES!!RES_0402-1.00K,1%,1/16W,CHIP,G21796-026!!
S!R4F5!!DEFAULT_RESISTOR_1000.000000OHM_2_1!!RES!!RES_0402-1.00K,1%,1/16W,CHIP,G21796-026!!
S!R6L16!!DEFAULT_RESISTOR_1000.000000OHM_2_1!!RES!!RES_0402-1.00K,1%,1/16W,CHIP,G21796-026!!
S!R9L11!!DEFAULT_RESISTOR_1000.000000OHM_2_1!!RES!!RES_0402-1.00K,1%,1/16W,CHIP,G21796-026!!
S!R7F22!45!DEFAULT_RESISTOR_1000.000000OHM_2_1!!RES!!RES_0402-1.00K,1%,1/16W,CHIP,G21796-026!!
S!R4E5!43!DEFAULT_RESISTOR_1000.000000OHM_2_1!!RES!!RES_0402-1.00K,1%,1/16W,CHIP,G21796-026!!
S!R4D58!19!DEFAULT_RESISTOR_1000.000000OHM_2_1!!RES!!RES_0402-1.00K,1%,1/16W,CHIP,G21796-026!!
S!R4E3!40!DEFAULT_RESISTOR_1000.000000OHM_2_1!!RES!!RES_0402-1.00K,1%,1/16W,CHIP,G21796-026!!
S!R1D8!!DEFAULT_RESISTOR_1000.000000OHM_2_1!!RES!!RES_0402-1.00K,1%,1/16W,CHIP,G21796-026!!
S!R1C28!!DEFAULT_RESISTOR_1000.000000OHM_2_1!!RES!!RES_0402-1.00K,1%,1/16W,CHIP,G21796-026!!
S!R1D6!!DEFAULT_RESISTOR_1000.000000OHM_2_1!!RES!!RES_0402-1.00K,1%,1/16W,CHIP,G21796-026!!
S!R1D36!18!DEFAULT_RESISTOR_1000.000000OHM_2_1!!RES!!RES_0402-1.00K,1%,1/16W,CHIP,G21796-026!!
S!R7D26!7!DEFAULT_RESISTOR_1000.000000OHM_2_1!!RES!!RES_0402-1.00K,1%,1/16W,CHIP,G21796-026!!
S!R3R1!14!DEFAULT_RESISTOR_1000.000000OHM_2_1!!RES!!RES_0402-1.00K,1%,1/16W,CHIP,G21796-026!!
S!R1L2!!!!RES!!RES_0402-10.0,1%,1/16W,CHIP,G21796-066!!
S!R4E8!1!DEFAULT_RESISTOR_10.000000OHM_2_1!YES!RES!!RES_0402-10.0,1%,1/16W,CHIP,G21796-066!!
S!R4D39!37!DEFAULT_RESISTOR_10.000000OHM_2_1!YES!RES!!RES_0402-10.0,1%,1/16W,CHIP,G21796-066!!
S!R1D4!!DEFAULT_RESISTOR_10.000000OHM_2_1!YES!RES!!RES_0402-10.0,1%,1/16W,CHIP,G21796-066!!
S!R1C21!!DEFAULT_RESISTOR_10.000000OHM_2_1!YES!RES!!RES_0402-10.0,1%,1/16W,CHIP,G21796-066!!
S!R3N19!407!DEFAULT_RESISTOR_10.000000OHM_2_1!!RES!!RES_0402-10.0,1%,1/16W,CHIP,G21796-066!!
S!R4E7!381!DEFAULT_RESISTOR_10.000000OHM_2_1!!RES!!RES_0402-10.0,1%,1/16W,CHIP,G21796-066!!
S!R6N8!!RES_0402-10.0_1%_1/16W_CHIP_G2A_10.0!!RES!!RES_0402-10.0,1%,1/16W,CHIP,G21796-066!!
S!R6N9!!RES_0402-10.0_1%_1/16W_CHIP_G2A_10.0!!RES!!RES_0402-10.0,1%,1/16W,CHIP,G21796-066!!
S!R1D51!!DEFAULT_RESISTOR_10.000000OHM_2_1!!RES!!RES_0402-10.0,1%,1/16W,CHIP,G21796-066!!
S!R7A19!!DEFAULT_RESISTOR_10.000000OHM_2_1!YES!RES!!RES_0402-10.0,1%,1/16W,CHIP,G21796-066!!
S!R7A14!!DEFAULT_RESISTOR_10.000000OHM_2_1!YES!RES!!RES_0402-10.0,1%,1/16W,CHIP,G21796-066!!
S!R3N9!!DEFAULT_RESISTOR_1000.000000OHM_2_1!!RES!!RES_0402-10.0,1%,1/16W,CHIP,G21796-066!!
S!R8B20!!DEFAULT_RESISTOR_1000.000000OHM_2_1!!RES!!RES_0402-10.0,1%,1/16W,CHIP,G21796-066!!
S!R8A1!!DEFAULT_RESISTOR_10.000000OHM_2_1!YES!RES!!RES_0402-10.0,1%,1/16W,CHIP,G21796-066!!
S!R7A7!!DEFAULT_RESISTOR_10.000000OHM_2_1!!RES!!RES_0402-10.0,1%,1/16W,CHIP,G21796-066!!
S!R1G5!9!DEFAULT_RESISTOR_10.000000OHM_2_1!YES!RES!!RES_0402-10.0,1%,1/16W,CHIP,G21796-066!!
S!R1B16!115!DEFAULT_RESISTOR_10.000000OHM_2_1!YES!RES!!RES_0402-10.0,1%,1/16W,CHIP,G21796-066!!
S!R1L32!!DEFAULT_RESISTOR_10.000000OHM_2_1!!RES!!RES_0402-10.0,1%,1/16W,CHIP,G21796-066!!
S!R1L30!!DEFAULT_RESISTOR_10.000000OHM_2_1!!RES!!RES_0402-10.0,1%,1/16W,CHIP,G21796-066!!
S!R1L25!!DEFAULT_RESISTOR_10.000000OHM_2_1!!RES!!RES_0402-10.0,1%,1/16W,CHIP,G21796-066!!
S!R1L24!!DEFAULT_RESISTOR_10.000000OHM_2_1!!RES!!RES_0402-10.0,1%,1/16W,CHIP,G21796-066!!
S!R1L20!!DEFAULT_RESISTOR_10.000000OHM_2_1!!RES!!RES_0402-10.0,1%,1/16W,CHIP,G21796-066!!
S!R1L18!!DEFAULT_RESISTOR_10.000000OHM_2_1!!RES!!RES_0402-10.0,1%,1/16W,CHIP,G21796-066!!
S!R1L14!!DEFAULT_RESISTOR_10.000000OHM_2_1!!RES!!RES_0402-10.0,1%,1/16W,CHIP,G21796-066!!
S!R1L11!!DEFAULT_RESISTOR_10.000000OHM_2_1!!RES!!RES_0402-10.0,1%,1/16W,CHIP,G21796-066!!
S!R3R7!!DEFAULT_RESISTOR_10.000000OHM_2_1!!RES!!RES_0402-10.0,1%,1/16W,CHIP,G21796-066!!
S!R6T3!!DEFAULT_RESISTOR_10.000000OHM_2_1!!RES!!RES_0402-10.0,1%,1/16W,CHIP,G21796-066!!
S!R4T3!5!DEFAULT_RESISTOR_10.000000OHM_2_1!!RES!!RES_0402-10.0,1%,1/16W,CHIP,G21796-066!!
S!R7M3!!DEFAULT_RESISTOR_10.000000OHM_2_1!!RES!!RES_0402-10.0,1%,1/16W,CHIP,G21796-066!!
S!R7M8!!DEFAULT_RESISTOR_10.000000OHM_2_1!!RES!!RES_0402-10.0,1%,1/16W,CHIP,G21796-066!!
S!R3R14!!DEFAULT_RESISTOR_10.000000OHM_2_1!!RES!!RES_0402-10.0,1%,1/16W,CHIP,G21796-066!!
S!R6T4!!DEFAULT_RESISTOR_10.000000OHM_2_1!!RES!!RES_0402-10.0,1%,1/16W,CHIP,G21796-066!!
S!R7G9!96!DEFAULT_RESISTOR_10.000000OHM_2_1!YES!RES!!RES_0402-10.0,1%,1/16W,CHIP,G21796-066!!
S!R4T4!3!DEFAULT_RESISTOR_10.000000OHM_2_1!!RES!!RES_0402-10.0,1%,1/16W,CHIP,G21796-066!!
S!R1D46!!DEFAULT_RESISTOR_10.000000OHM_2_1!!RES!!RES_0402-10.0,1%,1/16W,CHIP,G21796-066!!
S!R9P27!!DEFAULT_RESISTOR_10.000000OHM_2_1!!RES!!RES_0402-10.0,1%,1/16W,CHIP,G21796-066!!
S!R9P26!7!DEFAULT_RESISTOR_10.000000OHM_2_1!!RES!!RES_0402-10.0,1%,1/16W,CHIP,G21796-066!!
S!R1D47!!DEFAULT_RESISTOR_10.000000OHM_2_1!!RES!!RES_0402-10.0,1%,1/16W,CHIP,G21796-066!!
S!R1D48!!DEFAULT_RESISTOR_10.000000OHM_2_1!!RES!!RES_0402-10.0,1%,1/16W,CHIP,G21796-066!!
S!R9R4!!DEFAULT_RESISTOR_10.000000OHM_2_1!!RES!!RES_0402-10.0,1%,1/16W,CHIP,G21796-066!!
S!R1E1!!DEFAULT_RESISTOR_10.000000OHM_2_1!!RES!!RES_0402-10.0,1%,1/16W,CHIP,G21796-066!!
S!R1D28!33!!!RES!!RES_0402-100.0,1%,1/16W,EMPTY,G21796-017!!
S!R6P35!359!DEFAULT_RESISTOR_100.000000OHM_2_1!!RES!!RES_0402-100.0,1%,1/16W,EMPTY,G21796-017!!
S!R3L11!!DEFAULT_RESISTOR_100.000000OHM_2_1!!RES!!RES_0402-100.0,1%,1/16W,EMPTY,G21796-017!!
S!R9M7!!DEFAULT_RESISTOR_100.000000OHM_2_1!!RES!!RES_0402-100.0,1%,1/16W,EMPTY,G21796-017!!
S!R3P13!404!DEFAULT_RESISTOR_100.000000OHM_2_1!!RES!!RES_0402-100.0,1%,1/16W,EMPTY,G21796-017!!
S!R8B15!!!YES!RES!!RES_0402-100.0,1%,1/16W,EMPTY,G21796-017!!
S!R4U6!!!!RES!!RES_0402-100.0,1%,1/16W,EMPTY,G21796-017!!
S!R4L2!!!!RES!!RES_0402-100.0,1%,1/16W,EMPTY,G21796-017!!
S!R7U2!!!!RES!!RES_0402-100.0,1%,1/16W,EMPTY,G21796-017!!
S!R7L2!62!!!RES!!RES_0402-100.0,1%,1/16W,EMPTY,G21796-017!!
S!R6T7!!DEFAULT_RESISTOR_160.000000OHM_2_1!!RES!!RES_0402-150.0,1%,1/16W,CHIP,G21796-009!!
S!R6T6!!DEFAULT_RESISTOR_160.000000OHM_2_1!!RES!!RES_0402-150.0,1%,1/16W,CHIP,G21796-009!!
S!R1L15!!DEFAULT_RESISTOR_160.000000OHM_2_1!!RES!!RES_0402-150.0,1%,1/16W,CHIP,G21796-009!!
S!R3P40!!DEFAULT_RESISTOR_150.000000OHM_2_1!!RES!!RES_0402-150.0,1%,1/16W,CHIP,G21796-009!!
S!R7E1!!DEFAULT_RESISTOR_150.000000OHM_2_1!!RES!!RES_0402-150.0,1%,1/16W,CHIP,G21796-009!!
S!R7P21!!DEFAULT_RESISTOR_150.000000OHM_2_1!!RES!!RES_0402-150.0,1%,1/16W,CHIP,G21796-009!!
S!R1U35!!DEFAULT_RESISTOR_150.000000OHM_2_1!!RES!!RES_0402-150.0,1%,1/16W,CHIP,G21796-009!!
S!R7P5!!DEFAULT_RESISTOR_150.000000OHM_2_1!!RES!!RES_0402-150.0,1%,1/16W,CHIP,G21796-009!!
S!R1U41!!DEFAULT_RESISTOR_150.000000OHM_2_1!!RES!!RES_0402-150.0,1%,1/16W,CHIP,G21796-009!!
S!R2U40!!DEFAULT_RESISTOR_75.000000OHM_2_1!!RES!!RES_0402-150.0,1%,1/16W,CHIP,G21796-009!!
S!R2U41!!DEFAULT_RESISTOR_75.000000OHM_2_1!!RES!!RES_0402-150.0,1%,1/16W,CHIP,G21796-009!!
S!R4P17!!DEFAULT_RESISTOR_75.000000OHM_2_1!!RES!!RES_0402-150.0,1%,1/16W,CHIP,G21796-009!!
S!R4P20!!DEFAULT_RESISTOR_75.000000OHM_2_1!!RES!!RES_0402-150.0,1%,1/16W,CHIP,G21796-009!!
S!R7P28!20!DEFAULT_RESISTOR_75.000000OHM_2_1!!RES!!RES_0402-150.0,1%,1/16W,CHIP,G21796-009!!
S!R4R3!2!DEFAULT_RESISTOR_75.000000OHM_2_1!!RES!!RES_0402-150.0,1%,1/16W,CHIP,G21796-009!!
S!R4P24!!DEFAULT_RESISTOR_160.000000OHM_2_1!!RES!!RES_0402-150.0,1%,1/16W,CHIP,G21796-009!!
S!R4P23!!DEFAULT_RESISTOR_160.000000OHM_2_1!!RES!!RES_0402-150.0,1%,1/16W,CHIP,G21796-009!!
S!R8A14!!DEFAULT_RESISTOR_160.000000OHM_2_1!!RES!!RES_0402-150.0,1%,1/16W,CHIP,G21796-009!!
S!R8A13!!DEFAULT_RESISTOR_160.000000OHM_2_1!!RES!!RES_0402-150.0,1%,1/16W,CHIP,G21796-009!!
S!R9A11!!DEFAULT_RESISTOR_160.000000OHM_2_1!!RES!!RES_0402-150.0,1%,1/16W,CHIP,G21796-009!!
S!R4D51!342!DEFAULT_RESISTOR_150.000000OHM_2_1!!RES!!RES_0402-150.0,1%,1/16W,CHIP,G21796-009!!
S!R3P15!395!DEFAULT_RESISTOR_150.000000OHM_2_1!!RES!!RES_0402-150.0,1%,1/16W,CHIP,G21796-009!!
S!R7A17!!DEFAULT_RESISTOR_150.000000OHM_2_1!!RES!!RES_0402-150.0,1%,1/16W,CHIP,G21796-009!!
S!R1G7!8!DEFAULT_RESISTOR_150.000000OHM_2_1!!RES!!RES_0402-150.0,1%,1/16W,CHIP,G21796-009!!
S!R1B8!111!DEFAULT_RESISTOR_150.000000OHM_2_1!!RES!!RES_0402-150.0,1%,1/16W,CHIP,G21796-009!!
S!R7G24!91!DEFAULT_RESISTOR_150.000000OHM_2_1!!RES!!RES_0402-150.0,1%,1/16W,CHIP,G21796-009!!
S!R1D9!!DEFAULT_RESISTOR_150.000000OHM_2_1!!RES!!RES_0402-150.0,1%,1/16W,CHIP,G21796-009!!
S!R1L17!!DEFAULT_RESISTOR_150.000000OHM_2_1!!RES!!RES_0402-150.0,1%,1/16W,CHIP,G21796-009!!
S!R4R2!1!DEFAULT_RESISTOR_150.000000OHM_2_1!!RES!!RES_0402-150.0,1%,1/16W,CHIP,G21796-009!!
S!R7P18!2!DEFAULT_RESISTOR_150.000000OHM_2_1!!RES!!RES_0402-150.0,1%,1/16W,CHIP,G21796-009!!
S!R7P20!!DEFAULT_RESISTOR_150.000000OHM_2_1!!RES!!RES_0402-150.0,1%,1/16W,CHIP,G21796-009!!
S!R4E6!25!DEFAULT_RESISTOR_150.000000OHM_2_1!!RES!!RES_0402-150.0,1%,1/16W,CHIP,G21796-009!!
S!R4R4!!DEFAULT_RESISTOR_150.000000OHM_2_1!!RES!!RES_0402-150.0,1%,1/16W,CHIP,G21796-009!!
S!R6D9!148!DEFAULT_RESISTOR_150.000000OHM_2_1!!RES!!RES_0402-150.0,1%,1/16W,CHIP,G21796-009!!
S!R7P27!!DEFAULT_RESISTOR_150.000000OHM_2_1!!RES!!RES_0402-150.0,1%,1/16W,CHIP,G21796-009!!
S!R1G1!!DEFAULT_RESISTOR_2.000000OHM_2_1!!RES!!RES_0402-2,1.0%,1/16W,CHIP,G21796-274!!
S!R1G14!3!DEFAULT_RESISTOR_2.000000OHM_2_1!!RES!!RES_0402-2,1.0%,1/16W,CHIP,G21796-274!!
S!R9L8!!DEFAULT_RESISTOR_2.000000OHM_2_1!!RES!!RES_0402-2,1.0%,1/16W,CHIP,G21796-274!!
S!R9L3!!DEFAULT_RESISTOR_2.000000OHM_2_1!!RES!!RES_0402-2,1.0%,1/16W,CHIP,G21796-274!!
S!R6L14!!DEFAULT_RESISTOR_2.000000OHM_2_1!!RES!!RES_0402-2,1.0%,1/16W,CHIP,G21796-274!!
S!R4G1!!DEFAULT_RESISTOR_2.000000OHM_2_1!!RES!!RES_0402-2,1.0%,1/16W,CHIP,G21796-274!!
S!R4G20!!DEFAULT_RESISTOR_2.000000OHM_2_1!!RES!!RES_0402-2,1.0%,1/16W,CHIP,G21796-274!!
S!R6L3!!DEFAULT_RESISTOR_2.000000OHM_2_1!!RES!!RES_0402-2,1.0%,1/16W,CHIP,G21796-274!!
S!R1F4!!DEFAULT_RESISTOR_2.000000OHM_2_1!!RES!!RES_0402-2,1.0%,1/16W,CHIP,G21796-274!!
S!R4F3!!DEFAULT_RESISTOR_2.000000OHM_2_1!!RES!!RES_0402-2,1.0%,1/16W,CHIP,G21796-274!!
S!R9M2!!DEFAULT_RESISTOR_2.000000OHM_2_1!!RES!!RES_0402-2,1.0%,1/16W,CHIP,G21796-274!!
S!R6M2!!DEFAULT_RESISTOR_2.000000OHM_2_1!!RES!!RES_0402-2,1.0%,1/16W,CHIP,G21796-274!!
S!R7D5!!DEFAULT_RESISTOR_2260OHM_2_1!!RES!!RES_0402-2.26K,1.0%,1/16W,CHIP,G21796-311!!
S!R7D9!!DEFAULT_RESISTOR_2260OHM_2_1!!RES!!RES_0402-2.26K,1.0%,1/16W,CHIP,G21796-311!!
S!R7D11!!DEFAULT_RESISTOR_2260OHM_2_1!!RES!!RES_0402-2.26K,1.0%,1/16W,CHIP,G21796-311!!
S!R4E4!38!DEFAULT_RESISTOR_2260OHM_2_1!!RES!!RES_0402-2.26K,1.0%,1/16W,CHIP,G21796-311!!
S!R1D7!!DEFAULT_RESISTOR_2260OHM_2_1!!RES!!RES_0402-2.26K,1.0%,1/16W,CHIP,G21796-311!!
S!R8D24!!!!RES!!RES_0402-20.0,1%,1/16W,CHIP,G21796-173!!
S!R8D23!!!!RES!!RES_0402-20.0,1%,1/16W,CHIP,G21796-173!!
S!R1T8!!RES_0402-20.0_1%_1/16W_CHIP_G21A_0.0!!RES!!RES_0402-20.0,1%,1/16W,CHIP,G21796-173!!
S!R1T7!!RES_0402-20.0_1%_1/16W_CHIP_G21A_0.0!!RES!!RES_0402-20.0,1%,1/16W,CHIP,G21796-173!!
S!R9F23!!RES_0402-20.0_1%_1/16W_CHIP_G21A_0.0!!RES!!RES_0402-20.0,1%,1/16W,CHIP,G21796-173!!
S!R9F22!!RES_0402-20.0_1%_1/16W_CHIP_G21A_0.0!!RES!!RES_0402-20.0,1%,1/16W,CHIP,G21796-173!!
S!R2U31!!RES_0402-20.0_1%_1/16W_CHIP_G21A_0.0!!RES!!RES_0402-20.0,1%,1/16W,CHIP,G21796-173!!
S!R2U32!!RES_0402-20.0_1%_1/16W_CHIP_G21A_0.0!!RES!!RES_0402-20.0,1%,1/16W,CHIP,G21796-173!!
S!R9G12!!RES_0402-20.0_1%_1/16W_CHIP_G21A_0.0!!RES!!RES_0402-20.0,1%,1/16W,CHIP,G21796-173!!
S!R1U20!!RES_0402-20.0_1%_1/16W_CHIP_G21A_0.0!!RES!!RES_0402-20.0,1%,1/16W,CHIP,G21796-173!!
S!R1U19!!RES_0402-20.0_1%_1/16W_CHIP_G21A_0.0!!RES!!RES_0402-20.0,1%,1/16W,CHIP,G21796-173!!
S!R9G13!!RES_0402-20.0_1%_1/16W_CHIP_G21A_0.0!!RES!!RES_0402-20.0,1%,1/16W,CHIP,G21796-173!!
S!R9G15!!RES_0402-20.0_1%_1/16W_CHIP_G21A_0.0!!RES!!RES_0402-20.0,1%,1/16W,CHIP,G21796-173!!
S!R9G14!!RES_0402-20.0_1%_1/16W_CHIP_G21A_0.0!!RES!!RES_0402-20.0,1%,1/16W,CHIP,G21796-173!!
S!R1U31!!RES_0402-20.0_1%_1/16W_CHIP_G21A_0.0!!RES!!RES_0402-20.0,1%,1/16W,CHIP,G21796-173!!
S!R1U25!!RES_0402-20.0_1%_1/16W_CHIP_G21A_0.0!!RES!!RES_0402-20.0,1%,1/16W,CHIP,G21796-173!!
S!R9M14!!RES_0402-20.0_1%_1/16W_CHIP_G21A_0.0!!RES!!RES_0402-20.0,1%,1/16W,CHIP,G21796-173!!
S!R9M15!!RES_0402-20.0_1%_1/16W_CHIP_G21A_0.0!!RES!!RES_0402-20.0,1%,1/16W,CHIP,G21796-173!!
S!R9M13!!RES_0402-20.0_1%_1/16W_CHIP_G21A_0.0!!RES!!RES_0402-20.0,1%,1/16W,CHIP,G21796-173!!
S!R9M12!!RES_0402-20.0_1%_1/16W_CHIP_G21A_0.0!!RES!!RES_0402-20.0,1%,1/16W,CHIP,G21796-173!!
S!R2T55!!RES_0402-20.0_1%_1/16W_CHIP_G21A_0.0!!RES!!RES_0402-20.0,1%,1/16W,CHIP,G21796-173!!
S!R2T56!!RES_0402-20.0_1%_1/16W_CHIP_G21A_0.0!!RES!!RES_0402-20.0,1%,1/16W,CHIP,G21796-173!!
S!R8C11!!RES_0402-20.0_1%_1/16W_CHIP_G21A_0.0!!RES!!RES_0402-20.0,1%,1/16W,CHIP,G21796-173!!
S!R8C12!!RES_0402-20.0_1%_1/16W_CHIP_G21A_0.0!!RES!!RES_0402-20.0,1%,1/16W,CHIP,G21796-173!!
S!R8C20!!RES_0402-20.0_1%_1/16W_CHIP_G21A_0.0!!RES!!RES_0402-20.0,1%,1/16W,CHIP,G21796-173!!
S!R8C14!!RES_0402-20.0_1%_1/16W_CHIP_G21A_0.0!!RES!!RES_0402-20.0,1%,1/16W,CHIP,G21796-173!!
S!R3P24!402!RES_0402-20.0_1%_1/16W_CHIP_G21A_0.0!!RES!!RES_0402-20.0,1%,1/16W,CHIP,G21796-173!!
S!R7F25!93!RES_0402-20.0_1%_1/16W_CHIP_G21A_0.0!!RES!!RES_0402-20.0,1%,1/16W,CHIP,G21796-173!!
S!R2T49!!RES_0402-20.0_1%_1/16W_CHIP_G21A_0.0!!RES!!RES_0402-20.0,1%,1/16W,CHIP,G21796-173!!
S!R2U1!!RES_0402-20.0_1%_1/16W_CHIP_G21A_0.0!!RES!!RES_0402-20.0,1%,1/16W,CHIP,G21796-173!!
S!R7B2!!RES_0402-20.0_1%_1/16W_CHIP_G21A_0.0!!RES!!RES_0402-20.0,1%,1/16W,CHIP,G21796-173!!
S!R7B3!!RES_0402-20.0_1%_1/16W_CHIP_G21A_0.0!!RES!!RES_0402-20.0,1%,1/16W,CHIP,G21796-173!!
S!R1B7!107!RES_0402-20.0_1%_1/16W_CHIP_G21A_0.0!!RES!!RES_0402-20.0,1%,1/16W,CHIP,G21796-173!!
S!R1B6!108!RES_0402-20.0_1%_1/16W_CHIP_G21A_0.0!!RES!!RES_0402-20.0,1%,1/16W,CHIP,G21796-173!!
S!R2U10!!RES_0402-20.0_1%_1/16W_CHIP_G21A_0.0!!RES!!RES_0402-20.0,1%,1/16W,CHIP,G21796-173!!
S!R2U7!!RES_0402-20.0_1%_1/16W_CHIP_G21A_0.0!!RES!!RES_0402-20.0,1%,1/16W,CHIP,G21796-173!!
S!R8B28!!RES_0402-20.0_1%_1/16W_CHIP_G21A_0.0!!RES!!RES_0402-20.0,1%,1/16W,CHIP,G21796-173!!
S!R8B27!!RES_0402-20.0_1%_1/16W_CHIP_G21A_0.0!!RES!!RES_0402-20.0,1%,1/16W,CHIP,G21796-173!!
S!R1M9!9!RES_0402-20.0_1%_1/16W_CHIP_G21A_0.0!!RES!!RES_0402-20.0,1%,1/16W,CHIP,G21796-173!!
S!R9R8!2!RES_0402-20.0_1%_1/16W_CHIP_G21A_0.0!!RES!!RES_0402-20.0,1%,1/16W,CHIP,G21796-173!!
S!R1M8!8!RES_0402-20.0_1%_1/16W_CHIP_G21A_0.0!!RES!!RES_0402-20.0,1%,1/16W,CHIP,G21796-173!!
S!R9R7!3!RES_0402-20.0_1%_1/16W_CHIP_G21A_0.0!!RES!!RES_0402-20.0,1%,1/16W,CHIP,G21796-173!!
S!R2U9!!RES_0402-20.0_1%_1/16W_CHIP_G21A_0.0!!RES!!RES_0402-20.0,1%,1/16W,CHIP,G21796-173!!
S!R2U6!!RES_0402-20.0_1%_1/16W_CHIP_G21A_0.0!!RES!!RES_0402-20.0,1%,1/16W,CHIP,G21796-173!!
S!R8D6!!RES_0402-20.0_1%_1/16W_CHIP_G21A_0.0!!RES!!RES_0402-20.0,1%,1/16W,CHIP,G21796-173!!
S!R8D3!!RES_0402-20.0_1%_1/16W_CHIP_G21A_0.0!!RES!!RES_0402-20.0,1%,1/16W,CHIP,G21796-173!!
S!R8D7!!RES_0402-20.0_1%_1/16W_CHIP_G21A_0.0!!RES!!RES_0402-20.0,1%,1/16W,CHIP,G21796-173!!
S!R8D4!!RES_0402-20.0_1%_1/16W_CHIP_G21A_0.0!!RES!!RES_0402-20.0,1%,1/16W,CHIP,G21796-173!!
S!R1U10!!RES_0402-20.0_1%_1/16W_CHIP_G21A_0.0!!RES!!RES_0402-20.0,1%,1/16W,CHIP,G21796-173!!
S!R1U9!!RES_0402-20.0_1%_1/16W_CHIP_G21A_0.0!!RES!!RES_0402-20.0,1%,1/16W,CHIP,G21796-173!!
S!R2U33!!RES_0402-20.0_1%_1/16W_CHIP_G21A_0.0!!RES!!RES_0402-20.0,1%,1/16W,CHIP,G21796-173!!
S!R2U34!!RES_0402-20.0_1%_1/16W_CHIP_G21A_0.0!!RES!!RES_0402-20.0,1%,1/16W,CHIP,G21796-173!!
S!R8G5!!RES_0402-20.0_1%_1/16W_CHIP_G21A_0.0!!RES!!RES_0402-20.0,1%,1/16W,CHIP,G21796-173!!
S!R8G4!!RES_0402-20.0_1%_1/16W_CHIP_G21A_0.0!!RES!!RES_0402-20.0,1%,1/16W,CHIP,G21796-173!!
S!R4D44!351!RES_0402-20.0_1%_1/16W_CHIP_G21A_0.0!!RES!!RES_0402-20.0,1%,1/16W,CHIP,G21796-173!!
S!R7F26!94!RES_0402-20.0_1%_1/16W_CHIP_G21A_0.0!!RES!!RES_0402-20.0,1%,1/16W,CHIP,G21796-173!!
S!R3P23!401!RES_0402-20.0_1%_1/16W_CHIP_G21A_0.0!!RES!!RES_0402-20.0,1%,1/16W,CHIP,G21796-173!!
S!R4D43!352!RES_0402-20.0_1%_1/16W_CHIP_G21A_0.0!!RES!!RES_0402-20.0,1%,1/16W,CHIP,G21796-173!!
S!R8A8!!RES_0402-20.0_1%_1/16W_CHIP_G21A_0.0!!RES!!RES_0402-20.0,1%,1/16W,CHIP,G21796-173!!
S!R8A9!!RES_0402-20.0_1%_1/16W_CHIP_G21A_0.0!!RES!!RES_0402-20.0,1%,1/16W,CHIP,G21796-173!!
S!R3R9!!RES_0402-20.0_1%_1/16W_CHIP_G21A_0.0!!RES!!RES_0402-20.0,1%,1/16W,CHIP,G21796-173!!
S!R3R8!!RES_0402-20.0_1%_1/16W_CHIP_G21A_0.0!!RES!!RES_0402-20.0,1%,1/16W,CHIP,G21796-173!!
S!R6U14!!RES_0402-20.0_1%_1/16W_CHIP_G21A_0.0!!RES!!RES_0402-20.0,1%,1/16W,CHIP,G21796-173!!
S!R6U13!!RES_0402-20.0_1%_1/16W_CHIP_G21A_0.0!!RES!!RES_0402-20.0,1%,1/16W,CHIP,G21796-173!!
S!R4T10!11!RES_0402-20.0_1%_1/16W_CHIP_G21A_0.0!!RES!!RES_0402-20.0,1%,1/16W,CHIP,G21796-173!!
S!R7M4!!RES_0402-20.0_1%_1/16W_CHIP_G21A_0.0!!RES!!RES_0402-20.0,1%,1/16W,CHIP,G21796-173!!
S!R7M5!!RES_0402-20.0_1%_1/16W_CHIP_G21A_0.0!!RES!!RES_0402-20.0,1%,1/16W,CHIP,G21796-173!!
S!R4T9!10!RES_0402-20.0_1%_1/16W_CHIP_G21A_0.0!!RES!!RES_0402-20.0,1%,1/16W,CHIP,G21796-173!!
S!R6D7!149!RES_0402-1.00K_1%_1/16W_EMPTY_A_NA!!RES!!RES_0402-240,1.0%,1/16W,CHIP,G21796-294!!
S!R5D4!!DEFAULT_RESISTOR_240.000000OHM_2_1!!RES!!RES_0402-240,1.0%,1/16W,CHIP,G21796-294!!
S!R9M19!!DEFAULT_RESISTOR_240.000000OHM_2_1!!RES!!RES_0402-240,1.0%,1/16W,CHIP,G21796-294!!
S!R9M18!!DEFAULT_RESISTOR_240.000000OHM_2_1!!RES!!RES_0402-240,1.0%,1/16W,CHIP,G21796-294!!
S!R7P14!!DEFAULT_RESISTOR_240.000000OHM_2_1!!RES!!RES_0402-240,1.0%,1/16W,CHIP,G21796-294!!
S!R4P14!!DEFAULT_RESISTOR_240.000000OHM_2_1!!RES!!RES_0402-240,1.0%,1/16W,CHIP,G21796-294!!
S!R4P21!!DEFAULT_RESISTOR_240.000000OHM_2_1!!RES!!RES_0402-240,1.0%,1/16W,CHIP,G21796-294!!
S!R4C10!!DEFAULT_RESISTOR_240.000000OHM_2_1!!RES!!RES_0402-240,1.0%,1/16W,CHIP,G21796-294!!
S!R3R13!!DEFAULT_RESISTOR_750OHM_2_1!!RES!!RES_0402-240,1.0%,1/16W,CHIP,G21796-294!!
S!R3P60!!DEFAULT_RESISTOR_750OHM_2_1!!RES!!RES_0402-240,1.0%,1/16W,CHIP,G21796-294!!
S!R6T2!!DEFAULT_RESISTOR_750OHM_2_1!!RES!!RES_0402-240,1.0%,1/16W,CHIP,G21796-294!!
S!R6T1!!DEFAULT_RESISTOR_750OHM_2_1!!RES!!RES_0402-240,1.0%,1/16W,CHIP,G21796-294!!
S!R4T5!6!DEFAULT_RESISTOR_750OHM_2_1!!RES!!RES_0402-240,1.0%,1/16W,CHIP,G21796-294!!
S!R5D3!!DEFAULT_RESISTOR_240.000000OHM_2_1!!RES!!RES_0402-240,1.0%,1/16W,CHIP,G21796-294!!
S!R7M2!!DEFAULT_RESISTOR_750OHM_2_1!!RES!!RES_0402-240,1.0%,1/16W,CHIP,G21796-294!!
S!R7M7!!DEFAULT_RESISTOR_750OHM_2_1!!RES!!RES_0402-240,1.0%,1/16W,CHIP,G21796-294!!
S!R3D24!!DEFAULT_RESISTOR_240.000000OHM_2_1!!RES!!RES_0402-240,1.0%,1/16W,CHIP,G21796-294!!
S!R1T27!!DEFAULT_RESISTOR_240.000000OHM_2_1!!RES!!RES_0402-240,1.0%,1/16W,CHIP,G21796-294!!
S!R4T6!4!DEFAULT_RESISTOR_750OHM_2_1!!RES!!RES_0402-240,1.0%,1/16W,CHIP,G21796-294!!
S!R6D6!!DEFAULT_RESISTOR_240.000000OHM_2_1!!RES!!RES_0402-240,1.0%,1/16W,EMPTY,G21796-294!!
S!R3D12!!DEFAULT_RESISTOR_240.000000OHM_2_1!!RES!!RES_0402-240,1.0%,1/16W,EMPTY,G21796-294!!
S!R7P22!!!!RES!!RES_0402-240,1.0%,1/16W,EMPTY,G21796-294!!
S!R3D25!!DEFAULT_RESISTOR_240.000000OHM_2_1!!RES!!RES_0402-240,1.0%,1/16W,EMPTY,G21796-294!!
S!R6D14!!DEFAULT_RESISTOR_240.000000OHM_2_1!!RES!!RES_0402-240,1.0%,1/16W,EMPTY,G21796-294!!
S!R4P6!151!!!RES!!RES_0402-240,1.0%,1/16W,EMPTY,G21796-294!!
S!R6D10!147!!!RES!!RES_0402-240,1.0%,1/16W,EMPTY,G21796-294!!
S!R6D13!!!!RES!!RES_0402-240,1.0%,1/16W,EMPTY,G21796-294!!
S!R3D26!!!!RES!!RES_0402-240,1.0%,1/16W,EMPTY,G21796-294!!
S!R3D13!!!!RES!!RES_0402-240,1.0%,1/16W,EMPTY,G21796-294!!
S!R3D23!!!!RES!!RES_0402-240,1.0%,1/16W,EMPTY,G21796-294!!
S!R3D16!!!!RES!!RES_0402-240,1.0%,1/16W,EMPTY,G21796-294!!
S!R3D22!!!!RES!!RES_0402-240,1.0%,1/16W,EMPTY,G21796-294!!
S!R4P1!!!!RES!!RES_0402-240,1.0%,1/16W,EMPTY,G21796-294!!
S!R3D17!!!!RES!!RES_0402-240,1.0%,1/16W,EMPTY,G21796-294!!
S!R6D15!!!!RES!!RES_0402-240,1.0%,1/16W,EMPTY,G21796-294!!
S!R8D36!!!!RES!!RES_0402-33.2,1%,1/16W,CHIP,G21796-074!!
S!R4D36!!DEFAULT_RESISTOR_33.000000OHM_2_1!!RES!!RES_0402-33.2,1%,1/16W,CHIP,G21796-074!!
S!R4D37!!DEFAULT_RESISTOR_33.000000OHM_2_1!!RES!!RES_0402-33.2,1%,1/16W,CHIP,G21796-074!!
S!R2T28!!DEFAULT_RESISTOR_33.000000OHM_2_1!!RES!!RES_0402-33.2,1%,1/16W,CHIP,G21796-074!!
S!R8D22!!DEFAULT_RESISTOR_33.000000OHM_2_1!!RES!!RES_0402-33.2,1%,1/16W,CHIP,G21796-074!!
S!R2P4!!DEFAULT_RESISTOR_33.000000OHM_2_1!!RES!!RES_0402-33.2,1%,1/16W,CHIP,G21796-074!!
S!R2R2!!DEFAULT_RESISTOR_33.000000OHM_2_1!!RES!!RES_0402-33.2,1%,1/16W,CHIP,G21796-074!!
S!R9F34!!DEFAULT_RESISTOR_33.000000OHM_2_1!!RES!!RES_0402-33.2,1%,1/16W,CHIP,G21796-074!!
S!R1U40!!DEFAULT_RESISTOR_33.000000OHM_2_1!!RES!!RES_0402-33.2,1%,1/16W,CHIP,G21796-074!!
S!R1D30!!DEFAULT_RESISTOR_33.000000OHM_2_1!!RES!!RES_0402-33.2,1%,1/16W,CHIP,G21796-074!!
S!R1D26!!DEFAULT_RESISTOR_33.000000OHM_2_1!!RES!!RES_0402-33.2,1%,1/16W,CHIP,G21796-074!!
S!R6P45!!DEFAULT_RESISTOR_33.000000OHM_2_1!!RES!!RES_0402-33.2,1%,1/16W,CHIP,G21796-074!!
S!R4D65!!DEFAULT_RESISTOR_33.000000OHM_2_1!!RES!!RES_0402-33.2,1%,1/16W,CHIP,G21796-074!!
S!R9P3!!DEFAULT_RESISTOR_33.000000OHM_2_1!!RES!!RES_0402-33.2,1%,1/16W,CHIP,G21796-074!!
S!R1D1!!DEFAULT_RESISTOR_33.000000OHM_2_1!!RES!!RES_0402-33.2,1%,1/16W,CHIP,G21796-074!!
S!R4G19!!DEFAULT_RESISTOR_33.000000OHM_2_1!!RES!!RES_0402-33.2,1%,1/16W,CHIP,G21796-074!!
S!R4A6!!DEFAULT_RESISTOR_33.000000OHM_2_1!!RES!!RES_0402-33.2,1%,1/16W,CHIP,G21796-074!!
S!R1G8!!DEFAULT_RESISTOR_33.000000OHM_2_1!!RES!!RES_0402-33.2,1%,1/16W,CHIP,G21796-074!!
S!R1B4!!DEFAULT_RESISTOR_33.000000OHM_2_1!!RES!!RES_0402-33.2,1%,1/16W,CHIP,G21796-074!!
S!R4G15!!DEFAULT_RESISTOR_33.000000OHM_2_1!!RES!!RES_0402-33.2,1%,1/16W,CHIP,G21796-074!!
S!R4A4!!DEFAULT_RESISTOR_33.000000OHM_2_1!!RES!!RES_0402-33.2,1%,1/16W,CHIP,G21796-074!!
S!R7F23!!DEFAULT_RESISTOR_33.000000OHM_2_1!!RES!!RES_0402-33.2,1%,1/16W,CHIP,G21796-074!!
S!R7B1!!DEFAULT_RESISTOR_33.000000OHM_2_1!!RES!!RES_0402-33.2,1%,1/16W,CHIP,G21796-074!!
S!R1D33!!DEFAULT_RESISTOR_33.000000OHM_2_1!!RES!!RES_0402-33.2,1%,1/16W,CHIP,G21796-074!!
S!R1L29!!DEFAULT_RESISTOR_33.000000OHM_2_1!!RES!!RES_0402-33.2,1%,1/16W,CHIP,G21796-074!!
S!R9G10!!DEFAULT_RESISTOR_33.000000OHM_2_1!!RES!!RES_0402-33.2,1%,1/16W,CHIP,G21796-074!!
S!R9G16!!DEFAULT_RESISTOR_33.000000OHM_2_1!!RES!!RES_0402-33.2,1%,1/16W,CHIP,G21796-074!!
S!R8E20!!DEFAULT_RESISTOR_33.000000OHM_2_1!!RES!!RES_0402-33.2,1%,1/16W,CHIP,G21796-074!!
S!R8E24!!DEFAULT_RESISTOR_33.000000OHM_2_1!!RES!!RES_0402-33.2,1%,1/16W,CHIP,G21796-074!!
S!R7F3!!DEFAULT_RESISTOR_33.000000OHM_2_1!YES!RES!!RES_0402-33.2,1%,1/16W,CHIP,G21796-074!!
S!R3T1!!DEFAULT_RESISTOR_33.000000OHM_2_1!YES!RES!!RES_0402-33.2,1%,1/16W,CHIP,G21796-074!!
S!R7F29!!DEFAULT_RESISTOR_33.000000OHM_2_1!!RES!!RES_0402-33.2,1%,1/16W,CHIP,G21796-074!!
S!R3T10!!DEFAULT_RESISTOR_33.000000OHM_2_1!!RES!!RES_0402-33.2,1%,1/16W,CHIP,G21796-074!!
S!R7F37!!DEFAULT_RESISTOR_33.000000OHM_2_1!!RES!!RES_0402-33.2,1%,1/16W,CHIP,G21796-074!!
S!R3U1!!DEFAULT_RESISTOR_33.000000OHM_2_1!YES!RES!!RES_0402-33.2,1%,1/16W,CHIP,G21796-074!!
S!R8E9!!DEFAULT_RESISTOR_33.000000OHM_2_1!!RES!!RES_0402-33.2,1%,1/16W,CHIP,G21796-074!!
S!R8E10!!DEFAULT_RESISTOR_33.000000OHM_2_1!!RES!!RES_0402-33.2,1%,1/16W,CHIP,G21796-074!!
S!R8E13!!DEFAULT_RESISTOR_33.000000OHM_2_1!!RES!!RES_0402-33.2,1%,1/16W,CHIP,G21796-074!!
S!R8D11!!DEFAULT_RESISTOR_33.000000OHM_2_1!!RES!!RES_0402-33.2,1%,1/16W,CHIP,G21796-074!!
S!R7C14!!DEFAULT_RESISTOR_33.000000OHM_2_1!!RES!!RES_0402-33.2,1%,1/16W,CHIP,G21796-074!!
S!R9E16!!DEFAULT_RESISTOR_33.000000OHM_2_1!!RES!!RES_0402-33.2,1%,1/16W,CHIP,G21796-074!!
S!R2T47!!DEFAULT_RESISTOR_33.000000OHM_2_1!!RES!!RES_0402-33.2,1%,1/16W,CHIP,G21796-074!!
S!R8G1!!DEFAULT_RESISTOR_33.000000OHM_2_1!!RES!!RES_0402-33.2,1%,1/16W,CHIP,G21796-074!!
S!R3N28!!DEFAULT_RESISTOR_33.000000OHM_2_1!!RES!!RES_0402-33.2,1%,1/16W,CHIP,G21796-074!!
S!R3N24!!DEFAULT_RESISTOR_33.000000OHM_2_1!!RES!!RES_0402-33.2,1%,1/16W,CHIP,G21796-074!!
S!R3N26!!DEFAULT_RESISTOR_33.000000OHM_2_1!!RES!!RES_0402-33.2,1%,1/16W,CHIP,G21796-074!!
S!R1T31!!DEFAULT_RESISTOR_33.000000OHM_2_1!!RES!!RES_0402-33.2,1%,1/16W,CHIP,G21796-074!!
S!R7D14!!DEFAULT_RESISTOR_33.000000OHM_2_1!!RES!!RES_0402-33.2,1%,1/16W,CHIP,G21796-074!!
S!R3N25!!DEFAULT_RESISTOR_33.000000OHM_2_1!!RES!!RES_0402-33.2,1%,1/16W,CHIP,G21796-074!!
S!R2R10!!DEFAULT_RESISTOR_33.000000OHM_2_1!!RES!!RES_0402-33.2,1%,1/16W,CHIP,G21796-074!!
S!R2M3!!DEFAULT_RESISTOR_33.000000OHM_2_1!!RES!!RES_0402-33.2,1%,1/16W,CHIP,G21796-074!!
S!R2N1!!DEFAULT_RESISTOR_33.000000OHM_2_1!!RES!!RES_0402-33.2,1%,1/16W,CHIP,G21796-074!!
S!R2M7!!DEFAULT_RESISTOR_33.000000OHM_2_1!!RES!!RES_0402-33.2,1%,1/16W,CHIP,G21796-074!!
S!R2M1!!DEFAULT_RESISTOR_33.000000OHM_2_1!!RES!!RES_0402-33.2,1%,1/16W,CHIP,G21796-074!!
S!R2N26!!DEFAULT_RESISTOR_33.000000OHM_2_1!!RES!!RES_0402-33.2,1%,1/16W,CHIP,G21796-074!!
S!R2T14!!DEFAULT_RESISTOR_33.000000OHM_2_1!!RES!!RES_0402-33.2,1%,1/16W,CHIP,G21796-074!!
S!R3R3!16!DEFAULT_RESISTOR_33.000000OHM_2_1!!RES!!RES_0402-33.2,1%,1/16W,CHIP,G21796-074!!
S!R7D25!14!DEFAULT_RESISTOR_33.000000OHM_2_1!!RES!!RES_0402-33.2,1%,1/16W,CHIP,G21796-074!!
S!R7D24!13!DEFAULT_RESISTOR_33.000000OHM_2_1!!RES!!RES_0402-33.2,1%,1/16W,CHIP,G21796-074!!
S!R3P42!23!DEFAULT_RESISTOR_33.000000OHM_2_1!!RES!!RES_0402-33.2,1%,1/16W,CHIP,G21796-074!!
S!R3P43!24!DEFAULT_RESISTOR_33.000000OHM_2_1!!RES!!RES_0402-33.2,1%,1/16W,CHIP,G21796-074!!
S!R3P46!25!DEFAULT_RESISTOR_33.000000OHM_2_1!!RES!!RES_0402-33.2,1%,1/16W,CHIP,G21796-074!!
S!R7D34!12!DEFAULT_RESISTOR_33.000000OHM_2_1!!RES!!RES_0402-33.2,1%,1/16W,CHIP,G21796-074!!
S!R7D31!11!DEFAULT_RESISTOR_33.000000OHM_2_1!!RES!!RES_0402-33.2,1%,1/16W,CHIP,G21796-074!!
S!R7D29!10!DEFAULT_RESISTOR_33.000000OHM_2_1!!RES!!RES_0402-33.2,1%,1/16W,CHIP,G21796-074!!
S!R2T30!!DEFAULT_RESISTOR_33.000000OHM_2_1!!RES!!RES_0402-33.2,1%,1/16W,CHIP,G21796-074!!
S!R2T33!!DEFAULT_RESISTOR_33.000000OHM_2_1!!RES!!RES_0402-33.2,1%,1/16W,CHIP,G21796-074!!
S!R2T38!!DEFAULT_RESISTOR_33.000000OHM_2_1!!RES!!RES_0402-33.2,1%,1/16W,CHIP,G21796-074!!
S!R9F41!!DEFAULT_RESISTOR_33.000000OHM_2_1!!RES!!RES_0402-33.2,1%,1/16W,CHIP,G21796-074!!
S!R9F21!!DEFAULT_RESISTOR_33.000000OHM_2_1!!RES!!RES_0402-33.2,1%,1/16W,CHIP,G21796-074!!
S!R3N27!!DEFAULT_RESISTOR_33.000000OHM_2_1!!RES!!RES_0402-33.2,1%,1/16W,CHIP,G21796-074!!
S!R2T24!!DEFAULT_RESISTOR_33.000000OHM_2_1!!RES!!RES_0402-33.2,1%,1/16W,CHIP,G21796-074!!
S!R1U46!!DEFAULT_RESISTOR_33.000000OHM_2_1!!RES!!RES_0402-33.2,1%,1/16W,CHIP,G21796-074!!
S!R9G31!!DEFAULT_RESISTOR_33.000000OHM_2_1!!RES!!RES_0402-33.2,1%,1/16W,CHIP,G21796-074!!
S!R1U36!!DEFAULT_RESISTOR_33.000000OHM_2_1!!RES!!RES_0402-33.2,1%,1/16W,CHIP,G21796-074!!
S!R1U34!!DEFAULT_RESISTOR_33.000000OHM_2_1!!RES!!RES_0402-33.2,1%,1/16W,CHIP,G21796-074!!
S!R8E17!!DEFAULT_RESISTOR_33.000000OHM_2_1!!RES!!RES_0402-33.2,1%,1/16W,CHIP,G21796-074!!
S!R1L26!!DEFAULT_RESISTOR_33.000000OHM_2_1!!RES!!RES_0402-33.2,1%,1/16W,CHIP,G21796-074!!
S!R8F7!!DEFAULT_RESISTOR_33.000000OHM_2_1!!RES!!RES_0402-33.2,1%,1/16W,CHIP,G21796-074!!
S!R8E5!!DEFAULT_RESISTOR_33.000000OHM_2_1!!RES!!RES_0402-33.2,1%,1/16W,CHIP,G21796-074!!
S!R3T2!!DEFAULT_RESISTOR_33.000000OHM_2_1!!RES!!RES_0402-33.2,1%,1/16W,CHIP,G21796-074!!
S!R8F12!!DEFAULT_RESISTOR_33.000000OHM_2_1!!RES!!RES_0402-33.2,1%,1/16W,CHIP,G21796-074!!
S!R8F29!!DEFAULT_RESISTOR_33.000000OHM_2_1!!RES!!RES_0402-33.2,1%,1/16W,CHIP,G21796-074!!
S!R9E6!!DEFAULT_RESISTOR_33.000000OHM_2_1!!RES!!RES_0402-33.2,1%,1/16W,CHIP,G21796-074!!
S!R9E5!!DEFAULT_RESISTOR_33.000000OHM_2_1!!RES!!RES_0402-33.2,1%,1/16W,CHIP,G21796-074!!
S!R9E9!!DEFAULT_RESISTOR_33.000000OHM_2_1!!RES!!RES_0402-33.2,1%,1/16W,CHIP,G21796-074!!
S!R9E8!!DEFAULT_RESISTOR_33.000000OHM_2_1!!RES!!RES_0402-33.2,1%,1/16W,CHIP,G21796-074!!
S!R8F8!!DEFAULT_RESISTOR_33.000000OHM_2_1!!RES!!RES_0402-33.2,1%,1/16W,CHIP,G21796-074!!
S!R7C16!!DEFAULT_RESISTOR_33.000000OHM_2_1!!RES!!RES_0402-33.2,1%,1/16W,CHIP,G21796-074!!
S!R9A13!!DEFAULT_RESISTOR_33.000000OHM_2_1!!RES!!RES_0402-33.2,1%,1/16W,CHIP,G21796-074!!
S!R7F4!!DEFAULT_RESISTOR_33.000000OHM_2_1!!RES!!RES_0402-33.2,1%,1/16W,CHIP,G21796-074!!
S!R7D42!!!!RES!!RES_0402-4.75K,1%,1/16W,CHIP,G21796-072!!
S!R1B21!2!DEFAULT_RESISTOR_1500OHM_2_1!!RES!!RES_0402-4.75K,1%,1/16W,CHIP,G21796-072!!
S!R1F1!!DEFAULT_RESISTOR_1500OHM_2_1!!RES!!RES_0402-4.75K,1%,1/16W,CHIP,G21796-072!!
S!R2P17!!!!RES!!RES_0402-4.75K,1%,1/16W,CHIP,G21796-072!!
S!R7E21!!!!RES!!RES_0402-4.75K,1%,1/16W,CHIP,G21796-072!!
S!R2U48!!!!RES!!RES_0402-4.75K,1%,1/16W,CHIP,G21796-072!!
S!R7C17!!RES_0402-4.75K_1%_1/16W_EMPTY_A_NA!!RES!!RES_0402-4.75K,1%,1/16W,CHIP,G21796-072!!
S!R7D3!!DEFAULT_RESISTOR_10000OHM_2_1!!RES!!RES_0402-4.75K,1%,1/16W,CHIP,G21796-072!!
S!R2N32!!!!RES!!RES_0402-4.75K,1%,1/16W,CHIP,G21796-072!!
S!R8D14!!DEFAULT_RESISTOR_10000OHM_2_1!!RES!!RES_0402-4.75K,1%,1/16W,CHIP,G21796-072!!
S!R3P52!!!!RES!!RES_0402-4.75K,1%,1/16W,CHIP,G21796-072!!
S!R4C14!!!!RES!!RES_0402-4.75K,1%,1/16W,CHIP,G21796-072!!
S!R3P55!!!!RES!!RES_0402-4.75K,1%,1/16W,CHIP,G21796-072!!
S!R3P53!!!!RES!!RES_0402-4.75K,1%,1/16W,CHIP,G21796-072!!
S!R2N30!!!!RES!!RES_0402-4.75K,1%,1/16W,CHIP,G21796-072!!
S!R2N29!!!!RES!!RES_0402-4.75K,1%,1/16W,CHIP,G21796-072!!
S!R8D37!!!!RES!!RES_0402-4.75K,1%,1/16W,CHIP,G21796-072!!
S!R3R16!!!!RES!!RES_0402-4.75K,1%,1/16W,CHIP,G21796-072!!
S!R6M9!!!!RES!!RES_0402-4.75K,1%,1/16W,CHIP,G21796-072!!
S!R4D69!!DEFAULT_RESISTOR_47000OHM_2_1!!RES!!RES_0402-4.75K,1%,1/16W,CHIP,G21796-072!!
S!R4D70!!DEFAULT_RESISTOR_47000OHM_2_1!!RES!!RES_0402-4.75K,1%,1/16W,CHIP,G21796-072!!
S!R2T6!!DEFAULT_RESISTOR_10000OHM_2_1!!RES!!RES_0402-4.75K,1%,1/16W,CHIP,G21796-072!!
S!R4R5!!RES_0402-4.75K_1%_1/16W_CHIP_GA_4.75K!!RES!!RES_0402-4.75K,1%,1/16W,CHIP,G21796-072!!
S!R6P39!!RES_0402-4.75K_1%_1/16W_CHIP_GA_4.75K!!RES!!RES_0402-4.75K,1%,1/16W,CHIP,G21796-072!!
S!R8D26!!!!RES!!RES_0402-4.75K,1%,1/16W,CHIP,G21796-072!!
S!R1R5!!!!RES!!RES_0402-4.75K,1%,1/16W,CHIP,G21796-072!!
S!R8E32!!!!RES!!RES_0402-4.75K,1%,1/16W,CHIP,G21796-072!!
S!R9T5!!!!RES!!RES_0402-4.75K,1%,1/16W,CHIP,G21796-072!!
S!R1B24!!!!RES!!RES_0402-4.75K,1%,1/16W,CHIP,G21796-072!!
S!R8C25!!!!RES!!RES_0402-4.75K,1%,1/16W,CHIP,G21796-072!!
S!R9F52!!!!RES!!RES_0402-4.75K,1%,1/16W,CHIP,G21796-072!!
S!R9F30!!!!RES!!RES_0402-4.75K,1%,1/16W,CHIP,G21796-072!!
S!R3P44!!DEFAULT_RESISTOR_10000OHM_2_1!!RES!!RES_0402-4.75K,1%,1/16W,CHIP,G21796-072!!
S!R1L7!!!!RES!!RES_0402-4.75K,1%,1/16W,CHIP,G21796-072!!
S!R1D21!!!!RES!!RES_0402-4.75K,1%,1/16W,CHIP,G21796-072!!
S!R1R11!!RES_0402-4.75K_1%_1/16W_EMPTY_A_NA!!RES!!RES_0402-4.75K,1%,1/16W,CHIP,G21796-072!!
S!R8D25!!RES_0402-4.75K_1%_1/16W_CHIP_GA_4.75K!!RES!!RES_0402-4.75K,1%,1/16W,CHIP,G21796-072!!
S!R7D30!!RES_0402-4.75K_1%_1/16W_CHIP_GA_4.75K!!RES!!RES_0402-4.75K,1%,1/16W,CHIP,G21796-072!!
S!R8G23!!RES_0402-4.75K_1%_1/16W_CHIP_GA_4.75K!!RES!!RES_0402-4.75K,1%,1/16W,CHIP,G21796-072!!
S!R6P48!!DEFAULT_RESISTOR_47000OHM_2_1!!RES!!RES_0402-4.75K,1%,1/16W,CHIP,G21796-072!!
S!R8E14!!RES_0402-4.75K_1%_1/16W_CHIP_GA_4.75K!!RES!!RES_0402-4.75K,1%,1/16W,CHIP,G21796-072!!
S!R8G2!!RES_0402-4.75K_1%_1/16W_CHIP_GA_4.75K!!RES!!RES_0402-4.75K,1%,1/16W,CHIP,G21796-072!!
S!R2U2!!RES_0402-4.75K_1%_1/16W_CHIP_GA_4.75K!!RES!!RES_0402-4.75K,1%,1/16W,CHIP,G21796-072!!
S!R2U4!!RES_0402-4.75K_1%_1/16W_CHIP_GA_4.75K!!RES!!RES_0402-4.75K,1%,1/16W,CHIP,G21796-072!!
S!R8E19!!RES_0402-4.75K_1%_1/16W_CHIP_GA_4.75K!!RES!!RES_0402-4.75K,1%,1/16W,CHIP,G21796-072!!
S!R1D35!!RES_0402-4.75K_1%_1/16W_CHIP_GA_4.75K!!RES!!RES_0402-4.75K,1%,1/16W,CHIP,G21796-072!!
S!R2P13!!RES_0402-4.75K_1%_1/16W_CHIP_GA_4.75K!!RES!!RES_0402-4.75K,1%,1/16W,CHIP,G21796-072!!
S!R9F3!!RES_0402-4.75K_1%_1/16W_CHIP_GA_4.75K!!RES!!RES_0402-4.75K,1%,1/16W,CHIP,G21796-072!!
S!R9A21!!RES_0402-4.75K_1%_1/16W_CHIP_GA_4.75K!!RES!!RES_0402-4.75K,1%,1/16W,CHIP,G21796-072!!
S!R9A18!!RES_0402-4.75K_1%_1/16W_CHIP_GA_4.75K!!RES!!RES_0402-4.75K,1%,1/16W,CHIP,G21796-072!!
S!R8B25!!RES_0402-4.75K_1%_1/16W_CHIP_GA_4.75K!!RES!!RES_0402-4.75K,1%,1/16W,CHIP,G21796-072!!
S!R2M5!!RES_0402-4.75K_1%_1/16W_CHIP_GA_4.75K!!RES!!RES_0402-4.75K,1%,1/16W,CHIP,G21796-072!!
S!R2T3!!RES_0402-4.75K_1%_1/16W_CHIP_GA_4.75K!!RES!!RES_0402-4.75K,1%,1/16W,CHIP,G21796-072!!
S!R2P5!!RES_0402-4.75K_1%_1/16W_CHIP_GA_4.75K!!RES!!RES_0402-4.75K,1%,1/16W,CHIP,G21796-072!!
S!R8C1!!RES_0402-4.75K_1%_1/16W_CHIP_GA_4.75K!!RES!!RES_0402-4.75K,1%,1/16W,CHIP,G21796-072!!
S!R8C7!!RES_0402-4.75K_1%_1/16W_CHIP_GA_4.75K!!RES!!RES_0402-4.75K,1%,1/16W,CHIP,G21796-072!!
S!R8C9!!RES_0402-4.75K_1%_1/16W_CHIP_GA_4.75K!!RES!!RES_0402-4.75K,1%,1/16W,CHIP,G21796-072!!
S!R2T34!!RES_0402-4.75K_1%_1/16W_CHIP_GA_4.75K!!RES!!RES_0402-4.75K,1%,1/16W,CHIP,G21796-072!!
S!R2T35!!RES_0402-4.75K_1%_1/16W_CHIP_GA_4.75K!!RES!!RES_0402-4.75K,1%,1/16W,CHIP,G21796-072!!
S!R4D41!!RES_0402-4.75K_1%_1/16W_CHIP_GA_4.75K!!RES!!RES_0402-4.75K,1%,1/16W,CHIP,G21796-072!!
S!R2N7!!RES_0402-4.75K_1%_1/16W_CHIP_GA_4.75K!!RES!!RES_0402-4.75K,1%,1/16W,CHIP,G21796-072!!
S!R1E12!!RES_0402-4.75K_1%_1/16W_CHIP_GA_4.75K!!RES!!RES_0402-4.75K,1%,1/16W,CHIP,G21796-072!!
S!R7F33!7!RES_0402-4.75K_1%_1/16W_CHIP_GA_4.75K!!RES!!RES_0402-4.75K,1%,1/16W,CHIP,G21796-072!!
S!R7D6!!RES_0402-4.75K_1%_1/16W_CHIP_GA_4.75K!!RES!!RES_0402-4.75K,1%,1/16W,CHIP,G21796-072!!
S!R8C6!!RES_0402-4.75K_1%_1/16W_CHIP_GA_4.75K!!RES!!RES_0402-4.75K,1%,1/16W,CHIP,G21796-072!!
S!R8C2!!RES_0402-4.75K_1%_1/16W_CHIP_GA_4.75K!!RES!!RES_0402-4.75K,1%,1/16W,CHIP,G21796-072!!
S!R8B31!!RES_0402-4.75K_1%_1/16W_CHIP_GA_4.75K!!RES!!RES_0402-4.75K,1%,1/16W,CHIP,G21796-072!!
S!R2P3!!RES_0402-4.75K_1%_1/16W_CHIP_GA_4.75K!!RES!!RES_0402-4.75K,1%,1/16W,CHIP,G21796-072!!
S!R2M2!!RES_0402-4.75K_1%_1/16W_CHIP_GA_4.75K!!RES!!RES_0402-4.75K,1%,1/16W,CHIP,G21796-072!!
S!R9E21!!RES_0402-4.75K_1%_1/16W_CHIP_GA_4.75K!!RES!!RES_0402-4.75K,1%,1/16W,CHIP,G21796-072!!
S!R3N12!!RES_0402-4.75K_1%_1/16W_CHIP_GA_4.75K!!RES!!RES_0402-4.75K,1%,1/16W,CHIP,G21796-072!!
S!R3N11!!RES_0402-4.75K_1%_1/16W_CHIP_GA_4.75K!!RES!!RES_0402-4.75K,1%,1/16W,CHIP,G21796-072!!
S!R2P8!!RES_0402-4.75K_1%_1/16W_CHIP_GA_4.75K!!RES!!RES_0402-4.75K,1%,1/16W,CHIP,G21796-072!!
S!R2R7!!DEFAULT_RESISTOR_47000OHM_2_1!!RES!!RES_0402-4.75K,1%,1/16W,CHIP,G21796-072!!
S!R9T9!!RES_0402-4.75K_1%_1/16W_CHIP_GA_4.75K!!RES!!RES_0402-4.75K,1%,1/16W,CHIP,G21796-072!!
S!R7E7!!RES_0402-4.75K_1%_1/16W_CHIP_GA_4.75K!!RES!!RES_0402-4.75K,1%,1/16W,CHIP,G21796-072!!
S!R9F35!!RES_0402-4.75K_1%_1/16W_CHIP_GA_4.75K!!RES!!RES_0402-4.75K,1%,1/16W,CHIP,G21796-072!!
S!R2U30!!RES_0402-4.75K_1%_1/16W_CHIP_GA_4.75K!!RES!!RES_0402-4.75K,1%,1/16W,CHIP,G21796-072!!
S!R9F47!!RES_0402-4.75K_1%_1/16W_CHIP_GA_4.75K!!RES!!RES_0402-4.75K,1%,1/16W,CHIP,G21796-072!!
S!R9F55!!RES_0402-4.75K_1%_1/16W_CHIP_GA_4.75K!!RES!!RES_0402-4.75K,1%,1/16W,CHIP,G21796-072!!
S!R8D29!!RES_0402-4.75K_1%_1/16W_CHIP_GA_4.75K!!RES!!RES_0402-4.75K,1%,1/16W,CHIP,G21796-072!!
S!R8D31!!RES_0402-4.75K_1%_1/16W_CHIP_GA_4.75K!!RES!!RES_0402-4.75K,1%,1/16W,CHIP,G21796-072!!
S!R8B3!!DEFAULT_RESISTOR_4750OHM_2_1!!RES!!RES_0402-4.75K,1%,1/16W,CHIP,G21796-072!!
S!R8B5!!DEFAULT_RESISTOR_4750OHM_2_1!!RES!!RES_0402-4.75K,1%,1/16W,CHIP,G21796-072!!
S!R8B19!!DEFAULT_RESISTOR_4750OHM_2_1!!RES!!RES_0402-4.75K,1%,1/16W,CHIP,G21796-072!!
S!R8B18!!DEFAULT_RESISTOR_4750OHM_2_1!!RES!!RES_0402-4.75K,1%,1/16W,CHIP,G21796-072!!
S!R8B17!!DEFAULT_RESISTOR_4750OHM_2_1!!RES!!RES_0402-4.75K,1%,1/16W,CHIP,G21796-072!!
S!R8B16!!DEFAULT_RESISTOR_4750OHM_2_1!!RES!!RES_0402-4.75K,1%,1/16W,CHIP,G21796-072!!
S!R8B10!!DEFAULT_RESISTOR_4750OHM_2_1!!RES!!RES_0402-4.75K,1%,1/16W,CHIP,G21796-072!!
S!R8B8!!DEFAULT_RESISTOR_4750OHM_2_1!!RES!!RES_0402-4.75K,1%,1/16W,CHIP,G21796-072!!
S!R9F14!!RES_0402-4.75K_1%_1/16W_CHIP_GA_4.75K!!RES!!RES_0402-4.75K,1%,1/16W,CHIP,G21796-072!!
S!R9F9!!RES_0402-4.75K_1%_1/16W_CHIP_GA_4.75K!!RES!!RES_0402-4.75K,1%,1/16W,CHIP,G21796-072!!
S!R1T14!!RES_0402-4.75K_1%_1/16W_CHIP_GA_4.75K!!RES!!RES_0402-4.75K,1%,1/16W,CHIP,G21796-072!!
S!R9F16!!RES_0402-4.75K_1%_1/16W_CHIP_GA_4.75K!!RES!!RES_0402-4.75K,1%,1/16W,CHIP,G21796-072!!
S!R9F40!!RES_0402-4.75K_1%_1/16W_CHIP_GA_4.75K!!RES!!RES_0402-4.75K,1%,1/16W,CHIP,G21796-072!!
S!R7E10!2!RES_0402-4.75K_1%_1/16W_CHIP_GA_4.75K!!RES!!RES_0402-4.75K,1%,1/16W,CHIP,G21796-072!!
S!R7E11!2!RES_0402-4.75K_1%_1/16W_CHIP_GA_4.75K!!RES!!RES_0402-4.75K,1%,1/16W,CHIP,G21796-072!!
S!R3N13!!RES_0402-4.75K_1%_1/16W_CHIP_GA_4.75K!!RES!!RES_0402-4.75K,1%,1/16W,CHIP,G21796-072!!
S!R9F15!!RES_0402-4.75K_1%_1/16W_CHIP_GA_4.75K!!RES!!RES_0402-4.75K,1%,1/16W,CHIP,G21796-072!!
S!R2T11!!RES_0402-4.75K_1%_1/16W_CHIP_GA_4.75K!!RES!!RES_0402-4.75K,1%,1/16W,CHIP,G21796-072!!
S!R8E23!!RES_0402-4.75K_1%_1/16W_CHIP_GA_4.75K!!RES!!RES_0402-4.75K,1%,1/16W,CHIP,G21796-072!!
S!R8E22!!RES_0402-4.75K_1%_1/16W_CHIP_GA_4.75K!!RES!!RES_0402-4.75K,1%,1/16W,CHIP,G21796-072!!
S!R4D40!!RES_0402-4.75K_1%_1/16W_CHIP_GA_4.75K!!RES!!RES_0402-4.75K,1%,1/16W,CHIP,G21796-072!!
S!R1L27!!RES_0402-4.75K_1%_1/16W_CHIP_GA_4.75K!!RES!!RES_0402-4.75K,1%,1/16W,CHIP,G21796-072!!
S!R1U48!!RES_0402-4.75K_1%_1/16W_CHIP_GA_4.75K!!RES!!RES_0402-4.75K,1%,1/16W,CHIP,G21796-072!!
S!R1U45!!RES_0402-4.75K_1%_1/16W_CHIP_GA_4.75K!!RES!!RES_0402-4.75K,1%,1/16W,CHIP,G21796-072!!
S!R9G21!!RES_0402-4.75K_1%_1/16W_CHIP_GA_4.75K!!RES!!RES_0402-4.75K,1%,1/16W,CHIP,G21796-072!!
S!R4U3!!RES_0402-4.75K_1%_1/16W_CHIP_GA_4.75K!!RES!!RES_0402-4.75K,1%,1/16W,CHIP,G21796-072!!
S!R4U1!!RES_0402-4.75K_1%_1/16W_CHIP_GA_4.75K!!RES!!RES_0402-4.75K,1%,1/16W,CHIP,G21796-072!!
S!R8F24!!RES_0402-4.75K_1%_1/16W_CHIP_GA_4.75K!!RES!!RES_0402-4.75K,1%,1/16W,CHIP,G21796-072!!
S!R3T5!!RES_0402-4.75K_1%_1/16W_CHIP_GA_4.75K!YES!RES!!RES_0402-4.75K,1%,1/16W,CHIP,G21796-072!!
S!R8F14!!RES_0402-4.75K_1%_1/16W_CHIP_GA_4.75K!!RES!!RES_0402-4.75K,1%,1/16W,CHIP,G21796-072!!
S!R8F13!!RES_0402-4.75K_1%_1/16W_CHIP_GA_4.75K!!RES!!RES_0402-4.75K,1%,1/16W,CHIP,G21796-072!!
S!R8F34!!RES_0402-4.75K_1%_1/16W_CHIP_GA_4.75K!!RES!!RES_0402-4.75K,1%,1/16W,CHIP,G21796-072!!
S!R7F5!!RES_0402-4.75K_1%_1/16W_CHIP_GA_4.75K!YES!RES!!RES_0402-4.75K,1%,1/16W,CHIP,G21796-072!!
S!R1L28!!RES_0402-4.75K_1%_1/16W_CHIP_GA_4.75K!!RES!!RES_0402-4.75K,1%,1/16W,CHIP,G21796-072!!
S!R9F29!!RES_0402-4.75K_1%_1/16W_CHIP_GA_4.75K!!RES!!RES_0402-4.75K,1%,1/16W,CHIP,G21796-072!!
S!R7G7!!RES_0402-4.75K_1%_1/16W_CHIP_GA_4.75K!!RES!!RES_0402-4.75K,1%,1/16W,CHIP,G21796-072!!
S!R3R4!!RES_0402-4.75K_1%_1/16W_CHIP_GA_4.75K!!RES!!RES_0402-4.75K,1%,1/16W,CHIP,G21796-072!!
S!R3R10!!RES_0402-4.75K_1%_1/16W_CHIP_GA_4.75K!!RES!!RES_0402-4.75K,1%,1/16W,CHIP,G21796-072!!
S!R6M4!!RES_0402-4.75K_1%_1/16W_CHIP_GA_4.75K!!RES!!RES_0402-4.75K,1%,1/16W,CHIP,G21796-072!!
S!R2N27!!RES_0402-4.75K_1%_1/16W_CHIP_GA_4.75K!!RES!!RES_0402-4.75K,1%,1/16W,CHIP,G21796-072!!
S!R2T16!!DEFAULT_RESISTOR_75.000000OHM_2_1!!RES!!RES_0402-75,1.0%,1/16W,CHIP,G21796-267!!
S!R2T31!!DEFAULT_RESISTOR_75.000000OHM_2_1!!RES!!RES_0402-75,1.0%,1/16W,CHIP,G21796-267!!
S!R2T9!!DEFAULT_RESISTOR_75.000000OHM_2_1!!RES!!RES_0402-75,1.0%,1/16W,CHIP,G21796-267!!
S!R3P41!21!DEFAULT_RESISTOR_75.000000OHM_2_1!!RES!!RES_0402-75,1.0%,1/16W,CHIP,G21796-267!!
S!R2T43!!DEFAULT_RESISTOR_75.000000OHM_2_1!!RES!!RES_0402-75,1.0%,1/16W,CHIP,G21796-267!!
S!R7E2!1!DEFAULT_RESISTOR_75.000000OHM_2_1!!RES!!RES_0402-75,1.0%,1/16W,CHIP,G21796-267!!
S!U9F5!!!!K4B1G16!!K4B1G16_BGA1-IC,G38649-001!!
S!R9F25!!RES_0402-0.0_5%_1/16W_CHIP_G21A_0.0!!RES!!RES_0402-100.0,1%,1/16W,CHIP,G21796-017!!
S!R9B7!!RES_0402-0.0_5%_1/16W_CHIP_G21A_0.0!!RES!!RES_0402-100.0,1%,1/16W,CHIP,G21796-017!!
S!R2R8!!RES_0402-0.0_5%_1/16W_CHIP_G21A_0.0!!RES!!RES_0402-100.0,1%,1/16W,CHIP,G21796-017!!
S!R8D42!!!!RES!!RES_0402-100.0,1%,1/16W,CHIP,G21796-017!!
S!R1L39!!DEFAULT_RESISTOR_160.000000OHM_2_1!!RES!!RES_0402-100.0,1%,1/16W,CHIP,G21796-017!!
S!R1M3!!DEFAULT_RESISTOR_160.000000OHM_2_1!!RES!!RES_0402-100.0,1%,1/16W,CHIP,G21796-017!!
S!R9T7!!!!RES!!RES_0402-100.0,1%,1/16W,CHIP,G21796-017!!
S!R1B23!!!!RES!!RES_0402-100.0,1%,1/16W,CHIP,G21796-017!!
S!R7A13!!DEFAULT_RESISTOR_100.000000OHM_2_1!!RES!!RES_0402-100.0,1%,1/16W,CHIP,G21796-017!!
S!R1M4!!DEFAULT_RESISTOR_160.000000OHM_2_1!!RES!!RES_0402-100.0,1%,1/16W,CHIP,G21796-017!!
S!R3U2!100!DEFAULT_RESISTOR_100.000000OHM_2_1!!RES!!RES_0402-100.0,1%,1/16W,CHIP,G21796-017!!
S!R4P12!!DEFAULT_RESISTOR_100.000000OHM_2_1!!RES!!RES_0402-100.0,1%,1/16W,CHIP,G21796-017!!
S!R4P15!!DEFAULT_RESISTOR_100.000000OHM_2_1!!RES!!RES_0402-100.0,1%,1/16W,CHIP,G21796-017!!
S!R9U3!3!DEFAULT_RESISTOR_100.000000OHM_2_1!!RES!!RES_0402-100.0,1%,1/16W,CHIP,G21796-017!!
S!R2P20!!DEFAULT_RESISTOR_100.000000OHM_2_1!!RES!!RES_0402-100.0,1%,1/16W,CHIP,G21796-017!!
S!R1L41!!DEFAULT_RESISTOR_160.000000OHM_2_1!!RES!!RES_0402-100.0,1%,1/16W,CHIP,G21796-017!!
S!R9A9!!DEFAULT_RESISTOR_100.000000OHM_2_1!!RES!!RES_0402-100.0,1%,1/16W,CHIP,G21796-017!!
S!R1U37!!DEFAULT_RESISTOR_100.000000OHM_2_1!!RES!!RES_0402-100.0,1%,1/16W,CHIP,G21796-017!!
S!R1F2!!DEFAULT_RESISTOR_100.000000OHM_2_1!YES!RES!!RES_0402-100.0,1%,1/16W,CHIP,G21796-017!!
S!R1B22!3!DEFAULT_RESISTOR_100.000000OHM_2_1!YES!RES!!RES_0402-100.0,1%,1/16W,CHIP,G21796-017!!
S!R3D28!373!DEFAULT_RESISTOR_100.000000OHM_2_1!!RES!!RES_0402-100.0,1%,1/16W,CHIP,G21796-017!!
S!R3N21!389!DEFAULT_RESISTOR_100.000000OHM_2_1!!RES!!RES_0402-100.0,1%,1/16W,CHIP,G21796-017!!
S!R3E1!386!DEFAULT_RESISTOR_100.000000OHM_2_1!!RES!!RES_0402-100.0,1%,1/16W,CHIP,G21796-017!!
S!R3N20!388!DEFAULT_RESISTOR_100.000000OHM_2_1!!RES!!RES_0402-100.0,1%,1/16W,CHIP,G21796-017!!
S!R1E4!4!DEFAULT_RESISTOR_100.000000OHM_2_1!!RES!!RES_0402-100.0,1%,1/16W,CHIP,G21796-017!!
S!R1E8!1!DEFAULT_RESISTOR_100.000000OHM_2_1!!RES!!RES_0402-100.0,1%,1/16W,CHIP,G21796-017!!
S!R2T39!!DEFAULT_RESISTOR_100.000000OHM_2_1!!RES!!RES_0402-100.0,1%,1/16W,CHIP,G21796-017!!
S!R3M12!!DEFAULT_RESISTOR_100.000000OHM_2_1!YES!RES!!RES_0402-100.0,1%,1/16W,CHIP,G21796-017!!
S!R8D10!!DEFAULT_RESISTOR_100.000000OHM_2_1!!RES!!RES_0402-100.0,1%,1/16W,CHIP,G21796-017!!
S!R8C21!!DEFAULT_RESISTOR_100.000000OHM_2_1!!RES!!RES_0402-100.0,1%,1/16W,CHIP,G21796-017!!
S!R7P30!!DEFAULT_RESISTOR_100.000000OHM_2_1!!RES!!RES_0402-100.0,1%,1/16W,CHIP,G21796-017!!
S!R6P46!!DEFAULT_RESISTOR_100.000000OHM_2_1!!RES!!RES_0402-100.0,1%,1/16W,CHIP,G21796-017!!
S!R6T8!!DEFAULT_RESISTOR_100.000000OHM_2_1!!RES!!RES_0402-100.0,1%,1/16W,CHIP,G21796-017!!
S!R6T9!!DEFAULT_RESISTOR_100.000000OHM_2_1!!RES!!RES_0402-100.0,1%,1/16W,CHIP,G21796-017!!
S!R4C5!101!DEFAULT_RESISTOR_100.000000OHM_2_1!!RES!!RES_0402-100.0,1%,1/16W,CHIP,G21796-017!!
S!R4E14!107!DEFAULT_RESISTOR_100.000000OHM_2_1!!RES!!RES_0402-100.0,1%,1/16W,CHIP,G21796-017!!
S!R4E18!108!DEFAULT_RESISTOR_100.000000OHM_2_1!!RES!!RES_0402-100.0,1%,1/16W,CHIP,G21796-017!!
S!R6B2!1!DEFAULT_RESISTOR_100.000000OHM_2_1!!RES!!RES_0402-100.0,1%,1/16W,CHIP,G21796-017!!
S!R6N2!!DEFAULT_RESISTOR_100.000000OHM_2_1!!RES!!RES_0402-100.0,1%,1/16W,CHIP,G21796-017!!
S!R9N2!!DEFAULT_RESISTOR_100.000000OHM_2_1!!RES!!RES_0402-100.0,1%,1/16W,CHIP,G21796-017!!
S!R3B4!!DEFAULT_RESISTOR_100.000000OHM_2_1!!RES!!RES_0402-100.0,1%,1/16W,CHIP,G21796-017!!
S!R4E10!20!DEFAULT_RESISTOR_100.000000OHM_2_1!!RES!!RES_0402-100.0,1%,1/16W,CHIP,G21796-017!!
S!R9P1!!DEFAULT_RESISTOR_100.000000OHM_2_1!!RES!!RES_0402-100.0,1%,1/16W,CHIP,G21796-017!!
S!R1C12!!DEFAULT_RESISTOR_100.000000OHM_2_1!!RES!!RES_0402-100.0,1%,1/16W,CHIP,G21796-017!!
S!R1C4!!DEFAULT_RESISTOR_100.000000OHM_2_1!!RES!!RES_0402-100.0,1%,1/16W,CHIP,G21796-017!!
S!R4C1!102!DEFAULT_RESISTOR_100.000000OHM_2_1!!RES!!RES_0402-100.0,1%,1/16W,CHIP,G21796-017!!
S!R3M11!!DEFAULT_RESISTOR_100.000000OHM_2_1!YES!RES!!RES_0402-100.0,1%,1/16W,CHIP,G21796-017!!
S!R3P49!18!DEFAULT_RESISTOR_100.000000OHM_2_1!!RES!!RES_0402-100.0,1%,1/16W,CHIP,G21796-017!!
S!R7D32!3!DEFAULT_RESISTOR_100.000000OHM_2_1!!RES!!RES_0402-100.0,1%,1/16W,CHIP,G21796-017!!
S!R4P11!145!DEFAULT_RESISTOR_100.000000OHM_2_1!!RES!!RES_0402-100.0,1%,1/16W,CHIP,G21796-017!!
S!R6D1!146!DEFAULT_RESISTOR_100.000000OHM_2_1!!RES!!RES_0402-100.0,1%,1/16W,CHIP,G21796-017!!
S!R7P19!!DEFAULT_RESISTOR_100.000000OHM_2_1!!RES!!RES_0402-100.0,1%,1/16W,CHIP,G21796-017!!
S!R3D3!!DEFAULT_RESISTOR_100.000000OHM_2_1!!RES!!RES_0402-100.0,1%,1/16W,CHIP,G21796-017!!
S!R4P7!!!!RES!!RES_0402-49.9,1%,1/16W,CHIP,G21796-047!!
S!R7P15!!!!RES!!RES_0402-49.9,1%,1/16W,CHIP,G21796-047!!
S!R4R6!!DEFAULT_RESISTOR_150.000000OHM_2_1!!RES!!RES_0402-49.9,1%,1/16W,CHIP,G21796-047!!
S!R9B10!!DEFAULT_RESISTOR_51.100000OHM_2_1!!RES!!RES_0402-49.9,1%,1/16W,CHIP,G21796-047!!
S!R1M22!!DEFAULT_RESISTOR_150.000000OHM_2_1!!RES!!RES_0402-49.9,1%,1/16W,CHIP,G21796-047!!
S!R6M8!!DEFAULT_RESISTOR_150.000000OHM_2_1!!RES!!RES_0402-49.9,1%,1/16W,CHIP,G21796-047!!
S!R2T18!!!!RES!!RES_0402-49.9,1%,1/16W,CHIP,G21796-047!!
S!R1L16!!DEFAULT_RESISTOR_22.100000OHM_2_1!!RES!!RES_0402-49.9,1%,1/16W,CHIP,G21796-047!!
S!R5P2!!DEFAULT_RESISTOR_49.900000OHM_2_1!!RES!!RES_0402-49.9,1%,1/16W,CHIP,G21796-047!!
S!R5P3!!DEFAULT_RESISTOR_49.900000OHM_2_1!!RES!!RES_0402-49.9,1%,1/16W,CHIP,G21796-047!!
S!R6D5!!DEFAULT_RESISTOR_49.900000OHM_2_1!!RES!!RES_0402-49.9,1%,1/16W,CHIP,G21796-047!!
S!R8P1!!DEFAULT_RESISTOR_49.900000OHM_2_1!!RES!!RES_0402-49.9,1%,1/16W,CHIP,G21796-047!!
S!R8P2!!DEFAULT_RESISTOR_49.900000OHM_2_1!!RES!!RES_0402-49.9,1%,1/16W,CHIP,G21796-047!!
S!R3D9!!DEFAULT_RESISTOR_49.900000OHM_2_1!!RES!!RES_0402-49.9,1%,1/16W,CHIP,G21796-047!!
S!R5P4!!DEFAULT_RESISTOR_49.900000OHM_2_1!!RES!!RES_0402-49.9,1%,1/16W,CHIP,G21796-047!!
S!R5R1!!DEFAULT_RESISTOR_49.900000OHM_2_1!!RES!!RES_0402-49.9,1%,1/16W,CHIP,G21796-047!!
S!R8P3!!DEFAULT_RESISTOR_49.900000OHM_2_1!!RES!!RES_0402-49.9,1%,1/16W,CHIP,G21796-047!!
S!R8R1!!DEFAULT_RESISTOR_49.900000OHM_2_1!!RES!!RES_0402-49.9,1%,1/16W,CHIP,G21796-047!!
S!R8D20!!DEFAULT_RESISTOR_49.900000OHM_2_1!!RES!!RES_0402-49.9,1%,1/16W,CHIP,G21796-047!!
S!R8D19!!DEFAULT_RESISTOR_49.900000OHM_2_1!!RES!!RES_0402-49.9,1%,1/16W,CHIP,G21796-047!!
S!R2N31!!DEFAULT_RESISTOR_49.900000OHM_2_1!!RES!!RES_0402-49.9,1%,1/16W,CHIP,G21796-047!!
S!R2N19!!DEFAULT_RESISTOR_49.900000OHM_2_1!!RES!!RES_0402-49.9,1%,1/16W,CHIP,G21796-047!!
S!R8B29!!DEFAULT_RESISTOR_49.900000OHM_2_1!!RES!!RES_0402-49.9,1%,1/16W,CHIP,G21796-047!!
S!R2N22!!DEFAULT_RESISTOR_49.900000OHM_2_1!!RES!!RES_0402-49.9,1%,1/16W,CHIP,G21796-047!!
S!R3L13!!DEFAULT_RESISTOR_49.900000OHM_2_1!!RES!!RES_0402-49.9,1%,1/16W,CHIP,G21796-047!!
S!R9M6!!DEFAULT_RESISTOR_49.900000OHM_2_1!!RES!!RES_0402-49.9,1%,1/16W,CHIP,G21796-047!!
S!R4E9!24!DEFAULT_RESISTOR_110.000000OHM_2_1!!RES!!RES_0402-49.9,1%,1/16W,CHIP,G21796-047!!
S!R9P2!!DEFAULT_RESISTOR_110.000000OHM_2_1!!RES!!RES_0402-49.9,1%,1/16W,CHIP,G21796-047!!
S!R4P18!!DEFAULT_RESISTOR_49.900000OHM_2_1!!RES!!RES_0402-49.9,1%,1/16W,CHIP,G21796-047!!
S!R7P25!!DEFAULT_RESISTOR_49.900000OHM_2_1!!RES!!RES_0402-49.9,1%,1/16W,CHIP,G21796-047!!
S!R4P19!!DEFAULT_RESISTOR_49.900000OHM_2_1!!RES!!RES_0402-49.9,1%,1/16W,CHIP,G21796-047!!
S!R7P26!!DEFAULT_RESISTOR_49.900000OHM_2_1!!RES!!RES_0402-49.9,1%,1/16W,CHIP,G21796-047!!
S!R3D4!!DEFAULT_RESISTOR_49.900000OHM_2_1!!RES!!RES_0402-49.9,1%,1/16W,CHIP,G21796-047!!
S!R1U43!!DEFAULT_RESISTOR_49.900000OHM_2_1!!RES!!RES_0402-49.9,1%,1/16W,CHIP,G21796-047!!
S!R6F4!!DEFAULT_RESISTOR_49.900000OHM_2_1!!RES!!RES_0402-49.9,1%,1/16W,CHIP,G21796-047!!
S!R6F1!!DEFAULT_RESISTOR_49.900000OHM_2_1!!RES!!RES_0402-49.9,1%,1/16W,CHIP,G21796-047!!
S!R6F5!!DEFAULT_RESISTOR_49.900000OHM_2_1!!RES!!RES_0402-49.9,1%,1/16W,CHIP,G21796-047!!
S!R6F2!!DEFAULT_RESISTOR_49.900000OHM_2_1!!RES!!RES_0402-49.9,1%,1/16W,CHIP,G21796-047!!
S!R9B4!7!DEFAULT_RESISTOR_49.900000OHM_2_1!!RES!!RES_0402-49.9,1%,1/16W,CHIP,G21796-047!!
S!R9B5!6!DEFAULT_RESISTOR_49.900000OHM_2_1!!RES!!RES_0402-49.9,1%,1/16W,CHIP,G21796-047!!
S!R9R5!5!DEFAULT_RESISTOR_49.900000OHM_2_1!!RES!!RES_0402-49.9,1%,1/16W,CHIP,G21796-047!!
S!R9R6!6!DEFAULT_RESISTOR_49.900000OHM_2_1!!RES!!RES_0402-49.9,1%,1/16W,CHIP,G21796-047!!
S!R2T36!!DEFAULT_RESISTOR_49.900000OHM_2_1!!RES!!RES_0402-49.9,1%,1/16W,CHIP,G21796-047!!
S!R3D20!!DEFAULT_RESISTOR_49.900000OHM_2_1!!RES!!RES_0402-49.9,1%,1/16W,CHIP,G21796-047!!
S!R3D15!!DEFAULT_RESISTOR_49.900000OHM_2_1!!RES!!RES_0402-49.9,1%,1/16W,CHIP,G21796-047!!
S!R6D12!4!DEFAULT_RESISTOR_49.900000OHM_2_1!!RES!!RES_0402-49.9,1%,1/16W,CHIP,G21796-047!!
S!R6D8!3!DEFAULT_RESISTOR_49.900000OHM_2_1!!RES!!RES_0402-49.9,1%,1/16W,CHIP,G21796-047!!
S!R6B1!2!DEFAULT_RESISTOR_49.900000OHM_2_1!!RES!!RES_0402-49.9,1%,1/16W,CHIP,G21796-047!!
S!R6N1!!DEFAULT_RESISTOR_49.900000OHM_2_1!!RES!!RES_0402-49.9,1%,1/16W,CHIP,G21796-047!!
S!R9N1!!DEFAULT_RESISTOR_49.900000OHM_2_1!!RES!!RES_0402-49.9,1%,1/16W,CHIP,G21796-047!!
S!R3B2!!DEFAULT_RESISTOR_49.900000OHM_2_1!!RES!!RES_0402-49.9,1%,1/16W,CHIP,G21796-047!!
S!R3P45!17!DEFAULT_RESISTOR_49.900000OHM_2_1!!RES!!RES_0402-49.9,1%,1/16W,CHIP,G21796-047!!
S!R7D33!4!DEFAULT_RESISTOR_49.900000OHM_2_1!!RES!!RES_0402-49.9,1%,1/16W,CHIP,G21796-047!!
S!R6D2!150!DEFAULT_RESISTOR_49.900000OHM_2_1!!RES!!RES_0402-49.9,1%,1/16W,CHIP,G21796-047!!
S!R4P2!139!DEFAULT_RESISTOR_49.900000OHM_2_1!!RES!!RES_0402-49.9,1%,1/16W,CHIP,G21796-047!!
S!R4P3!140!DEFAULT_RESISTOR_49.900000OHM_2_1!!RES!!RES_0402-49.9,1%,1/16W,CHIP,G21796-047!!
S!R6D11!141!DEFAULT_RESISTOR_49.900000OHM_2_1!!RES!!RES_0402-49.9,1%,1/16W,CHIP,G21796-047!!
S!R4P4!142!DEFAULT_RESISTOR_49.900000OHM_2_1!!RES!!RES_0402-49.9,1%,1/16W,CHIP,G21796-047!!
S!R7P8!!DEFAULT_RESISTOR_49.900000OHM_2_1!!RES!!RES_0402-49.9,1%,1/16W,CHIP,G21796-047!!
S!R7P10!!DEFAULT_RESISTOR_49.900000OHM_2_1!!RES!!RES_0402-49.9,1%,1/16W,CHIP,G21796-047!!
S!R3D19!!DEFAULT_RESISTOR_49.900000OHM_2_1!!RES!!RES_0402-49.9,1%,1/16W,CHIP,G21796-047!!
S!R7P11!!DEFAULT_RESISTOR_49.900000OHM_2_1!!RES!!RES_0402-49.9,1%,1/16W,CHIP,G21796-047!!
S!EU1D2!17!!!ADM1278!!ADM1278_SM-IC,G99251-001!!
S!U9F4!!!!AST1250!!AST1250_BGA-IC,G85138-002!!
S!BT8G1!!!!BATTERY!!BATTERY_PLCLF-202168-001!!
S!C1C1!!DEFAULT_CAPACITOR_2.7e+08pF_2_1!!CAPP!!CAPP_2626-270UF,16V,20%,OSCON,A31228-047!!
S!C1E18!!DEFAULT_CAPACITOR_2.7e+08pF_2_1!!CAPP!!CAPP_2626-270UF,16V,20%,OSCON,A31228-047!!
S!C1C2!!DEFAULT_CAPACITOR_2.7e+08pF_2_1!!CAPP!!CAPP_2626-270UF,16V,20%,OSCON,A31228-047!!
S!C4E16!!DEFAULT_CAPACITOR_2.7e+08pF_2_1!!CAPP!!CAPP_2626-270UF,16V,20%,OSCON,A31228-047!!
S!C4D2!!DEFAULT_CAPACITOR_2.7e+08pF_2_1!!CAPP!!CAPP_2626-270UF,16V,20%,OSCON,A31228-047!!
S!C4C12!!DEFAULT_CAPACITOR_2.7e+08pF_2_1!!CAPP!!CAPP_2626-270UF,16V,20%,OSCON,A31228-047!!
S!C7G2!113!DEFAULT_CAPACITOR_2.7e+08pF_2_1!!CAPP!!CAPP_2626-270UF,16V,20%,OSCON,A31228-047!!
S!C7A19!36!DEFAULT_CAPACITOR_2.7e+08pF_2_1!!CAPP!!CAPP_2626-270UF,16V,20%,OSCON,A31228-047!!
S!C1B10!7!DEFAULT_CAPACITOR_2.7e+08pF_2_1!!CAPP!!CAPP_2626-270UF,16V,20%,OSCON,A31228-047!!
S!C4R1!!DEFAULT_CAPACITOR_4.7e+08pF_2_1!!CAPP!!CAPP_3018-470UF,2.5V,20%,ALUM,699013-049!!
S!C6R16!!DEFAULT_CAPACITOR_4.7e+08pF_2_1!!CAPP!!CAPP_3018-470UF,2.5V,20%,ALUM,699013-049!!
S!C3R4!!DEFAULT_CAPACITOR_4.7e+08pF_2_1!!CAPP!!CAPP_3018-470UF,2.5V,20%,ALUM,699013-049!!
S!C4E24!!DEFAULT_CAPACITOR_4.7e+08pF_2_1!!CAPP!!CAPP_3018-470UF,2.5V,20%,ALUM,699013-049!!
S!C3N14!!DEFAULT_CAPACITOR_4.7e+08pF_2_1!!CAPP!!CAPP_3018-470UF,2.5V,20%,ALUM,699013-049!!
S!C4C1!!DEFAULT_CAPACITOR_4.7e+08pF_2_1!!CAPP!!CAPP_3018-470UF,2.5V,20%,ALUM,699013-049!!
S!C6N9!!DEFAULT_CAPACITOR_4.7e+08pF_2_1!!CAPP!!CAPP_3018-470UF,2.5V,20%,ALUM,699013-049!!
S!C6P8!!DEFAULT_CAPACITOR_4.7e+08pF_2_1!!CAPP!!CAPP_3018-470UF,2.5V,20%,ALUM,699013-049!!
S!C6P18!!DEFAULT_CAPACITOR_4.7e+08pF_2_1!!CAPP!!CAPP_3018-470UF,2.5V,20%,ALUM,699013-049!!
S!C6P14!!DEFAULT_CAPACITOR_4.7e+08pF_2_1!!CAPP!!CAPP_3018-470UF,2.5V,20%,ALUM,699013-049!!
S!C6P23!!DEFAULT_CAPACITOR_4.7e+08pF_2_1!!CAPP!!CAPP_3018-470UF,2.5V,20%,ALUM,699013-049!!
S!C6R9!!DEFAULT_CAPACITOR_4.7e+08pF_2_1!!CAPP!!CAPP_3018-470UF,2.5V,20%,ALUM,699013-049!!
S!C6R3!!DEFAULT_CAPACITOR_4.7e+08pF_2_1!!CAPP!!CAPP_3018-470UF,2.5V,20%,ALUM,699013-049!!
S!C3N35!326!DEFAULT_CAPACITOR_4.7e+08pF_2_1!!CAPP!!CAPP_3018-470UF,2.5V,20%,ALUM,699013-049!!
S!C3N26!325!DEFAULT_CAPACITOR_4.7e+08pF_2_1!!CAPP!!CAPP_3018-470UF,2.5V,20%,ALUM,699013-049!!
S!C3N38!327!DEFAULT_CAPACITOR_4.7e+08pF_2_1!!CAPP!!CAPP_3018-470UF,2.5V,20%,ALUM,699013-049!!
S!C6R5!338!DEFAULT_CAPACITOR_4.7e+08pF_2_1!!CAPP!!CAPP_3018-470UF,2.5V,20%,ALUM,699013-049!!
S!C6R12!337!DEFAULT_CAPACITOR_4.7e+08pF_2_1!!CAPP!!CAPP_3018-470UF,2.5V,20%,ALUM,699013-049!!
S!C4E7!375!DEFAULT_CAPACITOR_4.7e+08pF_2_1!!CAPP!!CAPP_3018-470UF,2.5V,20%,ALUM,699013-049!!
S!C6N4!98!DEFAULT_CAPACITOR_4.7e+08pF_2_1!!CAPP!!CAPP_3018-470UF,2.5V,20%,ALUM,699013-049!!
S!C6N1!103!DEFAULT_CAPACITOR_4.7e+08pF_2_1!!CAPP!!CAPP_3018-470UF,2.5V,20%,ALUM,699013-049!!
S!C7G28!105!DEFAULT_CAPACITOR_4.7e+08pF_2_1!!CAPP!!CAPP_3018-470UF,2.5V,20%,ALUM,699013-049!!
S!C3U1!104!DEFAULT_CAPACITOR_4.7e+08pF_2_1!!CAPP!!CAPP_3018-470UF,2.5V,20%,ALUM,699013-049!!
S!C3U5!106!DEFAULT_CAPACITOR_4.7e+08pF_2_1!!CAPP!!CAPP_3018-470UF,2.5V,20%,ALUM,699013-049!!
S!C3U8!108!DEFAULT_CAPACITOR_4.7e+08pF_2_1!!CAPP!!CAPP_3018-470UF,2.5V,20%,ALUM,699013-049!!
S!C3L6!7!DEFAULT_CAPACITOR_4.7e+08pF_2_1!!CAPP!!CAPP_3018-470UF,2.5V,20%,ALUM,699013-049!!
S!C3L14!5!DEFAULT_CAPACITOR_4.7e+08pF_2_1!!CAPP!!CAPP_3018-470UF,2.5V,20%,ALUM,699013-049!!
S!C6A5!!DEFAULT_CAPACITOR_4.7e+08pF_2_1!!CAPP!!CAPP_3018-470UF,2.5V,20%,ALUM,699013-049!!
S!C4L5!1!DEFAULT_CAPACITOR_4.7e+08pF_2_1!!CAPP!!CAPP_3018-470UF,2.5V,20%,ALUM,699013-049!!
S!C9T5!!DEFAULT_CAPACITOR_4.7e+08pF_2_1!!CAPP!!CAPP_3018-470UF,2.5V,20%,ALUM,699013-049!!
S!C9U2!!DEFAULT_CAPACITOR_4.7e+08pF_2_1!!CAPP!!CAPP_3018-470UF,2.5V,20%,ALUM,699013-049!!
S!C9U9!!DEFAULT_CAPACITOR_4.7e+08pF_2_1!!CAPP!!CAPP_3018-470UF,2.5V,20%,ALUM,699013-049!!
S!C9U5!!DEFAULT_CAPACITOR_4.7e+08pF_2_1!!CAPP!!CAPP_3018-470UF,2.5V,20%,ALUM,699013-049!!
S!C9L9!3!DEFAULT_CAPACITOR_4.7e+08pF_2_1!!CAPP!!CAPP_3018-470UF,2.5V,20%,ALUM,699013-049!!
S!C9L12!12!DEFAULT_CAPACITOR_4.7e+08pF_2_1!!CAPP!!CAPP_3018-470UF,2.5V,20%,ALUM,699013-049!!
S!C9L4!27!DEFAULT_CAPACITOR_4.7e+08pF_2_1!!CAPP!!CAPP_3018-470UF,2.5V,20%,ALUM,699013-049!!
S!C9L2!16!DEFAULT_CAPACITOR_4.7e+08pF_2_1!!CAPP!!CAPP_3018-470UF,2.5V,20%,ALUM,699013-049!!
S!C9P18!!DEFAULT_CAPACITOR_4.7e+08pF_2_1!!CAPP!!CAPP_3018-470UF,2.5V,20%,ALUM,699013-049!!
S!C9P23!!DEFAULT_CAPACITOR_4.7e+08pF_2_1!!CAPP!!CAPP_3018-470UF,2.5V,20%,ALUM,699013-049!!
S!C9R3!!DEFAULT_CAPACITOR_4.7e+08pF_2_1!!CAPP!!CAPP_3018-470UF,2.5V,20%,ALUM,699013-049!!
S!C9R9!!DEFAULT_CAPACITOR_4.7e+08pF_2_1!!CAPP!!CAPP_3018-470UF,2.5V,20%,ALUM,699013-049!!
S!C9N24!!DEFAULT_CAPACITOR_4.7e+08pF_2_1!!CAPP!!CAPP_3018-470UF,2.5V,20%,ALUM,699013-049!!
S!C9P5!!DEFAULT_CAPACITOR_4.7e+08pF_2_1!!CAPP!!CAPP_3018-470UF,2.5V,20%,ALUM,699013-049!!
S!C9P8!!DEFAULT_CAPACITOR_4.7e+08pF_2_1!!CAPP!!CAPP_3018-470UF,2.5V,20%,ALUM,699013-049!!
S!C9N20!!DEFAULT_CAPACITOR_4.7e+08pF_2_1!!CAPP!!CAPP_3018-470UF,2.5V,20%,ALUM,699013-049!!
S!C9N11!!DEFAULT_CAPACITOR_4.7e+08pF_2_1!!CAPP!!CAPP_3018-470UF,2.5V,20%,ALUM,699013-049!!
S!C3L19!!DEFAULT_CAPACITOR_4.7e+08pF_2_1!!CAPP!!CAPP_SM-470UF,2V,20%,ALUM,699013-031!!
S!C3L18!!DEFAULT_CAPACITOR_4.7e+08pF_2_1!!CAPP!!CAPP_SM-470UF,2V,20%,ALUM,699013-031!!
S!C3L20!!DEFAULT_CAPACITOR_4.7e+08pF_2_1!!CAPP!!CAPP_SM-470UF,2V,20%,ALUM,699013-031!!
S!C3L21!!DEFAULT_CAPACITOR_4.7e+08pF_2_1!!CAPP!!CAPP_SM-470UF,2V,20%,ALUM,699013-031!!
S!C7A27!!DEFAULT_CAPACITOR_4.7e+08pF_2_1!!CAPP!!CAPP_SM-470UF,2V,20%,ALUM,699013-031!!
S!C2L46!!DEFAULT_CAPACITOR_4.7e+08pF_2_1!!CAPP!!CAPP_SM-470UF,2V,20%,ALUM,699013-031!!
S!C8A15!!DEFAULT_CAPACITOR_4.7e+08pF_2_1!!CAPP!!CAPP_SM-470UF,2V,20%,ALUM,699013-031!!
S!C2L25!!DEFAULT_CAPACITOR_4.7e+08pF_2_1!!CAPP!!CAPP_SM-470UF,2V,20%,ALUM,699013-031!!
S!C2U26!!DEFAULT_CAPACITOR_2.2e+07pF_2_1!YES!CAP!!CAP_0402-1.0UF,6.3V,10%,X6S,D97712-004!!
S!C1M3!!!!CAP!!CAP_0402-1.0UF,6.3V,10%,X6S,D97712-004!!
S!C2R12!!DEFAULT_CAPACITOR_1e+06pF_2_1!!CAP!!CAP_0402-1.0UF,6.3V,10%,X6S,D97712-004!!
S!C1M32!!DEFAULT_CAPACITOR_1e+06pF_2_1!!CAP!!CAP_0402-1.0UF,6.3V,10%,X6S,D97712-004!!
S!C1M25!!DEFAULT_CAPACITOR_1e+06pF_2_1!!CAP!!CAP_0402-1.0UF,6.3V,10%,X6S,D97712-004!!
S!C7F18!80!DEFAULT_CAPACITOR_1e+06pF_2_1!!CAP!!CAP_0402-1.0UF,6.3V,10%,X6S,D97712-004!!
S!C7F16!76!DEFAULT_CAPACITOR_1e+06pF_2_1!!CAP!!CAP_0402-1.0UF,6.3V,10%,X6S,D97712-004!!
S!C4D15!32!DEFAULT_CAPACITOR_1e+06pF_2_1!!CAP!!CAP_0402-1.0UF,6.3V,10%,X6S,D97712-004!!
S!C4D25!41!DEFAULT_CAPACITOR_1e+06pF_2_1!!CAP!!CAP_0402-1.0UF,6.3V,10%,X6S,D97712-004!!
S!C1C7!!DEFAULT_CAPACITOR_1e+06pF_2_1!!CAP!!CAP_0402-1.0UF,6.3V,10%,X6S,D97712-004!!
S!C7A37!!DEFAULT_CAPACITOR_1e+06pF_2_1!!CAP!!CAP_0402-1.0UF,6.3V,10%,X6S,D97712-004!!
S!C7B1!!DEFAULT_CAPACITOR_1e+06pF_2_1!!CAP!!CAP_0402-1.0UF,6.3V,10%,X6S,D97712-004!!
S!C1G27!29!DEFAULT_CAPACITOR_1e+06pF_2_1!!CAP!!CAP_0402-1.0UF,6.3V,10%,X6S,D97712-004!!
S!C1G23!26!DEFAULT_CAPACITOR_1e+06pF_2_1!!CAP!!CAP_0402-1.0UF,6.3V,10%,X6S,D97712-004!!
S!C1B6!104!DEFAULT_CAPACITOR_1e+06pF_2_1!!CAP!!CAP_0402-1.0UF,6.3V,10%,X6S,D97712-004!!
S!C1B3!105!DEFAULT_CAPACITOR_1e+06pF_2_1!!CAP!!CAP_0402-1.0UF,6.3V,10%,X6S,D97712-004!!
S!C1C13!!DEFAULT_CAPACITOR_1e+06pF_2_1!!CAP!!CAP_0402-1.0UF,6.3V,10%,X6S,D97712-004!!
S!C1M21!!DEFAULT_CAPACITOR_100000pF_2_1!!CAP!!CAP_0402-1.0UF,6.3V,10%,X6S,D97712-004!!
S!C3P4!418!DEFAULT_CAPACITOR_1e+06pF_2_1!!CAP!!CAP_0402-1.0UF,6.3V,10%,X6S,D97712-004!!
S!C4D31!356!DEFAULT_CAPACITOR_1e+06pF_2_1!!CAP!!CAP_0402-1.0UF,6.3V,10%,X6S,D97712-004!!
S!C3P3!415!DEFAULT_CAPACITOR_1e+06pF_2_1!!CAP!!CAP_0402-1.0UF,6.3V,10%,X6S,D97712-004!!
S!C4D36!345!DEFAULT_CAPACITOR_1e+06pF_2_1!!CAP!!CAP_0402-1.0UF,6.3V,10%,X6S,D97712-004!!
S!C8A7!!DEFAULT_CAPACITOR_1e+06pF_2_1!!CAP!!CAP_0402-1.0UF,6.3V,10%,X6S,D97712-004!!
S!C4D27!!DEFAULT_CAPACITOR_1e+06pF_2_1!!CAP!!CAP_0402-1.0UF,6.3V,10%,X6S,D97712-004!!
S!C4D23!!DEFAULT_CAPACITOR_1e+06pF_2_1!!CAP!!CAP_0402-1.0UF,6.3V,10%,X6S,D97712-004!!
S!C2L8!!DEFAULT_CAPACITOR_1e+06pF_2_1!!CAP!!CAP_0402-1.0UF,6.3V,10%,X6S,D97712-004!!
S!C2N1!!DEFAULT_CAPACITOR_1e+06pF_2_1!!CAP!!CAP_0402-1.0UF,6.3V,10%,X6S,D97712-004!!
S!C3M19!!DEFAULT_CAPACITOR_1e+06pF_2_1!!CAP!!CAP_0402-1.0UF,6.3V,10%,X6S,D97712-004!!
S!C3M20!7!DEFAULT_CAPACITOR_1e+06pF_2_1!!CAP!!CAP_0402-1.0UF,6.3V,10%,X6S,D97712-004!!
S!C2M6!!DEFAULT_CAPACITOR_1e+06pF_2_1!!CAP!!CAP_0402-1.0UF,6.3V,10%,X6S,D97712-004!!
S!C3M27!!DEFAULT_CAPACITOR_1e+06pF_2_1!!CAP!!CAP_0402-1.0UF,6.3V,10%,X6S,D97712-004!!
S!C3M29!!DEFAULT_CAPACITOR_1e+06pF_2_1!!CAP!!CAP_0402-1.0UF,6.3V,10%,X6S,D97712-004!!
S!C2M8!!DEFAULT_CAPACITOR_1e+06pF_2_1!!CAP!!CAP_0402-1.0UF,6.3V,10%,X6S,D97712-004!!
S!C1L18!!DEFAULT_CAPACITOR_1e+06pF_2_1!!CAP!!CAP_0402-1.0UF,6.3V,10%,X6S,D97712-004!!
S!C1L10!!DEFAULT_CAPACITOR_1e+06pF_2_1!!CAP!!CAP_0402-1.0UF,6.3V,10%,X6S,D97712-004!!
S!C8F4!!DEFAULT_CAPACITOR_1e+06pF_2_1!!CAP!!CAP_0402-1.0UF,6.3V,10%,X6S,D97712-004!!
S!C4C4!!DEFAULT_CAPACITOR_1e+06pF_2_1!!CAP!!CAP_0402-1.0UF,6.3V,10%,X6S,D97712-004!!
S!C3L29!15!DEFAULT_CAPACITOR_1e+06pF_2_1!!CAP!!CAP_0402-1.0UF,6.3V,10%,X6S,D97712-004!!
S!C3L1!!DEFAULT_CAPACITOR_1e+06pF_2_1!!CAP!!CAP_0402-1.0UF,6.3V,10%,X6S,D97712-004!!
S!C3N40!1!DEFAULT_CAPACITOR_1e+06pF_2_1!!CAP!!CAP_0402-1.0UF,6.3V,10%,X6S,D97712-004!!
S!C3M46!2!DEFAULT_CAPACITOR_1e+06pF_2_1!!CAP!!CAP_0402-1.0UF,6.3V,10%,X6S,D97712-004!!
S!C3C2!11!DEFAULT_CAPACITOR_1e+06pF_2_1!!CAP!!CAP_0402-1.0UF,6.3V,10%,X6S,D97712-004!!
S!C3C1!12!DEFAULT_CAPACITOR_1e+06pF_2_1!!CAP!!CAP_0402-1.0UF,6.3V,10%,X6S,D97712-004!!
S!C4T2!87!DEFAULT_CAPACITOR_1e+06pF_2_1!!CAP!!CAP_0402-1.0UF,6.3V,10%,X6S,D97712-004!!
S!C4T1!88!DEFAULT_CAPACITOR_1e+06pF_2_1!!CAP!!CAP_0402-1.0UF,6.3V,10%,X6S,D97712-004!!
S!C4F1!!DEFAULT_CAPACITOR_1e+06pF_2_1!!CAP!!CAP_0402-1.0UF,6.3V,10%,X6S,D97712-004!!
S!C4F3!!DEFAULT_CAPACITOR_1e+06pF_2_1!!CAP!!CAP_0402-1.0UF,6.3V,10%,X6S,D97712-004!!
S!C7F2!!DEFAULT_CAPACITOR_1e+06pF_2_1!YES!CAP!!CAP_0402-1.0UF,6.3V,10%,X6S,D97712-004!!
S!C3T4!!DEFAULT_CAPACITOR_1e+06pF_2_1!YES!CAP!!CAP_0402-1.0UF,6.3V,10%,X6S,D97712-004!!
S!C7C20!413!DEFAULT_CAPACITOR_1e+06pF_2_1!!CAP!!CAP_0402-1.0UF,6.3V,10%,X6S,D97712-004!!
S!C4E28!326!DEFAULT_CAPACITOR_1e+06pF_2_1!!CAP!!CAP_0402-1.0UF,6.3V,10%,X6S,D97712-004!!
S!C4D14!!DEFAULT_CAPACITOR_1e+06pF_2_1!!CAP!!CAP_0402-1.0UF,6.3V,10%,X6S,D97712-004!!
S!C4D6!!DEFAULT_CAPACITOR_1e+06pF_2_1!!CAP!!CAP_0402-1.0UF,6.3V,10%,X6S,D97712-004!!
S!C1T51!!DEFAULT_CAPACITOR_1e+06pF_2_1!!CAP!!CAP_0402-1.0UF,6.3V,10%,X6S,D97712-004!!
S!C3N5!!DEFAULT_CAPACITOR_1e+06pF_2_1!!CAP!!CAP_0402-1.0UF,6.3V,10%,X6S,D97712-004!!
S!C3N20!!DEFAULT_CAPACITOR_1e+06pF_2_1!!CAP!!CAP_0402-1.0UF,6.3V,10%,X6S,D97712-004!!
S!C3N4!!DEFAULT_CAPACITOR_1e+06pF_2_1!!CAP!!CAP_0402-1.0UF,6.3V,10%,X6S,D97712-004!!
S!C3N15!!DEFAULT_CAPACITOR_1e+06pF_2_1!!CAP!!CAP_0402-1.0UF,6.3V,10%,X6S,D97712-004!!
S!C3N2!!DEFAULT_CAPACITOR_1e+06pF_2_1!!CAP!!CAP_0402-1.0UF,6.3V,10%,X6S,D97712-004!!
S!C3N17!!DEFAULT_CAPACITOR_1e+06pF_2_1!!CAP!!CAP_0402-1.0UF,6.3V,10%,X6S,D97712-004!!
S!C3N18!!DEFAULT_CAPACITOR_1e+06pF_2_1!!CAP!!CAP_0402-1.0UF,6.3V,10%,X6S,D97712-004!!
S!C3N6!!DEFAULT_CAPACITOR_1e+06pF_2_1!!CAP!!CAP_0402-1.0UF,6.3V,10%,X6S,D97712-004!!
S!C3N3!!DEFAULT_CAPACITOR_1e+06pF_2_1!!CAP!!CAP_0402-1.0UF,6.3V,10%,X6S,D97712-004!!
S!C3N16!!DEFAULT_CAPACITOR_1e+06pF_2_1!!CAP!!CAP_0402-1.0UF,6.3V,10%,X6S,D97712-004!!
S!C3N19!!DEFAULT_CAPACITOR_1e+06pF_2_1!!CAP!!CAP_0402-1.0UF,6.3V,10%,X6S,D97712-004!!
S!C3N7!!DEFAULT_CAPACITOR_1e+06pF_2_1!!CAP!!CAP_0402-1.0UF,6.3V,10%,X6S,D97712-004!!
S!C2N11!!DEFAULT_CAPACITOR_1e+06pF_2_1!!CAP!!CAP_0402-1.0UF,6.3V,10%,X6S,D97712-004!!
S!C3N1!!DEFAULT_CAPACITOR_1e+06pF_2_1!!CAP!!CAP_0402-1.0UF,6.3V,10%,X6S,D97712-004!!
S!C2N3!!DEFAULT_CAPACITOR_1e+06pF_2_1!!CAP!!CAP_0402-1.0UF,6.3V,10%,X6S,D97712-004!!
S!C2N12!!DEFAULT_CAPACITOR_1e+06pF_2_1!!CAP!!CAP_0402-1.0UF,6.3V,10%,X6S,D97712-004!!
S!C2N9!!DEFAULT_CAPACITOR_1e+06pF_2_1!!CAP!!CAP_0402-1.0UF,6.3V,10%,X6S,D97712-004!!
S!C2N4!!DEFAULT_CAPACITOR_1e+06pF_2_1!!CAP!!CAP_0402-1.0UF,6.3V,10%,X6S,D97712-004!!
S!C3N21!!DEFAULT_CAPACITOR_1e+06pF_2_1!!CAP!!CAP_0402-1.0UF,6.3V,10%,X6S,D97712-004!!
S!C2M16!!DEFAULT_CAPACITOR_1e+06pF_2_1!!CAP!!CAP_0402-1.0UF,6.3V,10%,X6S,D97712-004!!
S!C2N25!!DEFAULT_CAPACITOR_1e+06pF_2_1!!CAP!!CAP_0402-1.0UF,6.3V,10%,X6S,D97712-004!!
S!C2N18!!DEFAULT_CAPACITOR_1e+06pF_2_1!!CAP!!CAP_0402-1.0UF,6.3V,10%,X6S,D97712-004!!
S!C2N15!!DEFAULT_CAPACITOR_1e+06pF_2_1!!CAP!!CAP_0402-1.0UF,6.3V,10%,X6S,D97712-004!!
S!C2N2!!DEFAULT_CAPACITOR_1e+06pF_2_1!!CAP!!CAP_0402-1.0UF,6.3V,10%,X6S,D97712-004!!
S!C2N13!!DEFAULT_CAPACITOR_1e+06pF_2_1!!CAP!!CAP_0402-1.0UF,6.3V,10%,X6S,D97712-004!!
S!C2M20!!DEFAULT_CAPACITOR_1e+06pF_2_1!!CAP!!CAP_0402-1.0UF,6.3V,10%,X6S,D97712-004!!
S!C2M18!!DEFAULT_CAPACITOR_1e+06pF_2_1!!CAP!!CAP_0402-1.0UF,6.3V,10%,X6S,D97712-004!!
S!C2N20!!DEFAULT_CAPACITOR_1e+06pF_2_1!!CAP!!CAP_0402-1.0UF,6.3V,10%,X6S,D97712-004!!
S!C2M21!!DEFAULT_CAPACITOR_1e+06pF_2_1!!CAP!!CAP_0402-1.0UF,6.3V,10%,X6S,D97712-004!!
S!C2N19!!DEFAULT_CAPACITOR_1e+06pF_2_1!!CAP!!CAP_0402-1.0UF,6.3V,10%,X6S,D97712-004!!
S!C2N8!!DEFAULT_CAPACITOR_1e+06pF_2_1!!CAP!!CAP_0402-1.0UF,6.3V,10%,X6S,D97712-004!!
S!C2N7!!DEFAULT_CAPACITOR_1e+06pF_2_1!!CAP!!CAP_0402-1.0UF,6.3V,10%,X6S,D97712-004!!
S!C3M43!!DEFAULT_CAPACITOR_1e+06pF_2_1!!CAP!!CAP_0402-1.0UF,6.3V,10%,X6S,D97712-004!!
S!C3M38!!DEFAULT_CAPACITOR_1e+06pF_2_1!!CAP!!CAP_0402-1.0UF,6.3V,10%,X6S,D97712-004!!
S!C2M19!!DEFAULT_CAPACITOR_1e+06pF_2_1!!CAP!!CAP_0402-1.0UF,6.3V,10%,X6S,D97712-004!!
S!C2M22!!DEFAULT_CAPACITOR_1e+06pF_2_1!!CAP!!CAP_0402-1.0UF,6.3V,10%,X6S,D97712-004!!
S!C3N22!!DEFAULT_CAPACITOR_1e+06pF_2_1!!CAP!!CAP_0402-1.0UF,6.3V,10%,X6S,D97712-004!!
S!C3N23!!DEFAULT_CAPACITOR_1e+06pF_2_1!!CAP!!CAP_0402-1.0UF,6.3V,10%,X6S,D97712-004!!
S!C2N16!!DEFAULT_CAPACITOR_1e+06pF_2_1!!CAP!!CAP_0402-1.0UF,6.3V,10%,X6S,D97712-004!!
S!C2N26!!DEFAULT_CAPACITOR_1e+06pF_2_1!!CAP!!CAP_0402-1.0UF,6.3V,10%,X6S,D97712-004!!
S!C3N25!!DEFAULT_CAPACITOR_1e+06pF_2_1!!CAP!!CAP_0402-1.0UF,6.3V,10%,X6S,D97712-004!!
S!C1U18!!DEFAULT_CAPACITOR_1e+06pF_2_1!!CAP!!CAP_0402-1.0UF,6.3V,10%,X6S,D97712-004!!
S!C1C18!!DEFAULT_CAPACITOR_1e+06pF_2_1!!CAP!!CAP_0402-1.0UF,6.3V,10%,X6S,D97712-004!!
S!C2T33!!DEFAULT_CAPACITOR_1e+06pF_2_1!!CAP!!CAP_0402-1.0UF,6.3V,10%,X6S,D97712-004!!
S!C2T28!!DEFAULT_CAPACITOR_1e+06pF_2_1!!CAP!!CAP_0402-1.0UF,6.3V,10%,X6S,D97712-004!!
S!C2T19!!DEFAULT_CAPACITOR_1e+06pF_2_1!!CAP!!CAP_0402-1.0UF,6.3V,10%,X6S,D97712-004!!
S!C2T38!!DEFAULT_CAPACITOR_1e+06pF_2_1!!CAP!!CAP_0402-1.0UF,6.3V,10%,X6S,D97712-004!!
S!C2T31!!DEFAULT_CAPACITOR_1e+06pF_2_1!!CAP!!CAP_0402-1.0UF,6.3V,10%,X6S,D97712-004!!
S!C3M21!!DEFAULT_CAPACITOR_1e+06pF_2_1!!CAP!!CAP_0402-1.0UF,6.3V,10%,X6S,D97712-004!!
S!C3M22!3!DEFAULT_CAPACITOR_1e+06pF_2_1!!CAP!!CAP_0402-1.0UF,6.3V,10%,X6S,D97712-004!!
S!C3M30!!DEFAULT_CAPACITOR_1e+06pF_2_1!!CAP!!CAP_0402-1.0UF,6.3V,10%,X6S,D97712-004!!
S!C3P42!10!DEFAULT_CAPACITOR_1e+06pF_2_1!!CAP!!CAP_0402-1.0UF,6.3V,10%,X6S,D97712-004!!
S!C4C3!!DEFAULT_CAPACITOR_1e+06pF_2_1!!CAP!!CAP_0402-1.0UF,6.3V,10%,X6S,D97712-004!!
S!C1T28!!DEFAULT_CAPACITOR_1e+06pF_2_1!!CAP!!CAP_0402-1.0UF,6.3V,10%,X6S,D97712-004!!
S!C1T32!!DEFAULT_CAPACITOR_1e+06pF_2_1!!CAP!!CAP_0402-1.0UF,6.3V,10%,X6S,D97712-004!!
S!C1U6!!DEFAULT_CAPACITOR_1e+06pF_2_1!!CAP!!CAP_0402-1.0UF,6.3V,10%,X6S,D97712-004!!
S!C1T55!!DEFAULT_CAPACITOR_1e+06pF_2_1!!CAP!!CAP_0402-1.0UF,6.3V,10%,X6S,D97712-004!!
S!C1U7!!DEFAULT_CAPACITOR_1e+06pF_2_1!!CAP!!CAP_0402-1.0UF,6.3V,10%,X6S,D97712-004!!
S!C1T46!!DEFAULT_CAPACITOR_1e+06pF_2_1!!CAP!!CAP_0402-1.0UF,6.3V,10%,X6S,D97712-004!!
S!C1T31!!DEFAULT_CAPACITOR_1e+06pF_2_1!!CAP!!CAP_0402-1.0UF,6.3V,10%,X6S,D97712-004!!
S!C1T35!!DEFAULT_CAPACITOR_1e+06pF_2_1!!CAP!!CAP_0402-1.0UF,6.3V,10%,X6S,D97712-004!!
S!C1T49!!DEFAULT_CAPACITOR_1e+06pF_2_1!!CAP!!CAP_0402-1.0UF,6.3V,10%,X6S,D97712-004!!
S!C9F12!!DEFAULT_CAPACITOR_1e+06pF_2_1!!CAP!!CAP_0402-1.0UF,6.3V,10%,X6S,D97712-004!!
S!C1T19!!DEFAULT_CAPACITOR_1e+06pF_2_1!!CAP!!CAP_0402-1.0UF,6.3V,10%,X6S,D97712-004!!
S!C1T21!!DEFAULT_CAPACITOR_1e+06pF_2_1!!CAP!!CAP_0402-1.0UF,6.3V,10%,X6S,D97712-004!!
S!C1M37!!DEFAULT_CAPACITOR_1e+06pF_2_1!!CAP!!CAP_0402-1.0UF,6.3V,10%,X6S,D97712-004!!
S!C3M31!!DEFAULT_CAPACITOR_1e+06pF_2_1!!CAP!!CAP_0402-1.0UF,6.3V,10%,X6S,D97712-004!!
S!C2N5!!DEFAULT_CAPACITOR_1e+06pF_2_1!!CAP!!CAP_0402-1.0UF,6.3V,10%,X6S,D97712-004!!
S!C2M7!!DEFAULT_CAPACITOR_1e+06pF_2_1!!CAP!!CAP_0402-1.0UF,6.3V,10%,X6S,D97712-004!!
S!C2M9!3!DEFAULT_CAPACITOR_1e+06pF_2_1!!CAP!!CAP_0402-1.0UF,6.3V,10%,X6S,D97712-004!!
S!C4E25!70!DEFAULT_CAPACITOR_1e+06pF_2_1!!CAP!!CAP_0402-1.0UF,6.3V,10%,X6S,D97712-004!!
S!C4E6!57!DEFAULT_CAPACITOR_1e+06pF_2_1!!CAP!!CAP_0402-1.0UF,6.3V,10%,X6S,D97712-004!!
S!C4C14!43!DEFAULT_CAPACITOR_1e+06pF_2_1!!CAP!!CAP_0402-1.0UF,6.3V,10%,X6S,D97712-004!!
S!C1L5!!DEFAULT_CAPACITOR_1e+06pF_2_1!!CAP!!CAP_0402-1.0UF,6.3V,10%,X6S,D97712-004!!
S!C9A6!!DEFAULT_CAPACITOR_1e+06pF_2_1!!CAP!!CAP_0402-1.0UF,6.3V,10%,X6S,D97712-004!!
S!C3M42!!DEFAULT_CAPACITOR_1e+06pF_2_1!!CAP!!CAP_0402-1.0UF,6.3V,10%,X6S,D97712-004!!
S!C3M39!!DEFAULT_CAPACITOR_1e+06pF_2_1!!CAP!!CAP_0402-1.0UF,6.3V,10%,X6S,D97712-004!!
S!C3N32!!DEFAULT_CAPACITOR_1e+06pF_2_1!!CAP!!CAP_0402-1.0UF,6.3V,10%,X6S,D97712-004!!
S!C7C19!!DEFAULT_CAPACITOR_1e+06pF_2_1!!CAP!!CAP_0402-1.0UF,6.3V,10%,X6S,D97712-004!!
S!C1T12!!DEFAULT_CAPACITOR_1e+06pF_2_1!!CAP!!CAP_0402-1.0UF,6.3V,10%,X6S,D97712-004!!
S!C1U8!!DEFAULT_CAPACITOR_1e+06pF_2_1!!CAP!!CAP_0402-1.0UF,6.3V,10%,X6S,D97712-004!!
S!C7G35!52!DEFAULT_CAPACITOR_1e+06pF_2_1!!CAP!!CAP_0402-1.0UF,6.3V,10%,X6S,D97712-004!!
S!C7G42!15!DEFAULT_CAPACITOR_1e+06pF_2_1!!CAP!!CAP_0402-1.0UF,6.3V,10%,X6S,D97712-004!!
S!C7A18!22!DEFAULT_CAPACITOR_1e+06pF_2_1!!CAP!!CAP_0402-1.0UF,6.3V,10%,X6S,D97712-004!!
S!C7A26!10!DEFAULT_CAPACITOR_1e+06pF_2_1!!CAP!!CAP_0402-1.0UF,6.3V,10%,X6S,D97712-004!!
S!C1A2!87!DEFAULT_CAPACITOR_1e+06pF_2_1!!CAP!!CAP_0402-1.0UF,6.3V,10%,X6S,D97712-004!!
S!C1A11!109!DEFAULT_CAPACITOR_1e+06pF_2_1!!CAP!!CAP_0402-1.0UF,6.3V,10%,X6S,D97712-004!!
S!C1G4!1!DEFAULT_CAPACITOR_1e+06pF_2_1!!CAP!!CAP_0402-1.0UF,6.3V,10%,X6S,D97712-004!!
S!C1F21!8!DEFAULT_CAPACITOR_1e+06pF_2_1!!CAP!!CAP_0402-1.0UF,6.3V,10%,X6S,D97712-004!!
S!C1E23!!DEFAULT_CAPACITOR_1e+06pF_2_1!!CAP!!CAP_0402-1.0UF,6.3V,10%,X6S,D97712-004!!
S!C1E6!9!DEFAULT_CAPACITOR_1e+06pF_2_1!!CAP!!CAP_0402-1.0UF,6.3V,10%,X6S,D97712-004!!
S!C1D15!11!DEFAULT_CAPACITOR_1e+06pF_2_1!!CAP!!CAP_0402-1.0UF,6.3V,10%,X6S,D97712-004!!
S!C1D5!!DEFAULT_CAPACITOR_1e+06pF_2_1!!CAP!!CAP_0402-1.0UF,6.3V,10%,X6S,D97712-004!!
S!C1C3!!DEFAULT_CAPACITOR_1e+06pF_2_1!!CAP!!CAP_0402-1.0UF,6.3V,10%,X6S,D97712-004!!
S!C1L20!!!!CAP!!CAP_0402LF-0.01UF,25V,10%,X7R,A36096-045!!
S!C1M35!!!!CAP!!CAP_0402LF-0.01UF,25V,10%,X7R,A36096-045!!
S!C1M34!!!!CAP!!CAP_0402LF-0.01UF,25V,10%,X7R,A36096-045!!
S!C9T1!!!!CAP!!CAP_0402LF-0.01UF,25V,10%,X7R,A36096-045!!
S!C1B17!!!!CAP!!CAP_0402LF-0.01UF,25V,10%,X7R,A36096-045!!
S!C1M31!!DEFAULT_CAPACITOR_10000pF_2_1!!CAP!!CAP_0402LF-0.01UF,25V,10%,X7R,A36096-045!!
S!C1M28!!DEFAULT_CAPACITOR_10000pF_2_1!!CAP!!CAP_0402LF-0.01UF,25V,10%,X7R,A36096-045!!
S!C1M30!!DEFAULT_CAPACITOR_10000pF_2_1!!CAP!!CAP_0402LF-0.01UF,25V,10%,X7R,A36096-045!!
S!C2L31!!DEFAULT_CAPACITOR_10000pF_2_1!!CAP!!CAP_0402LF-0.01UF,25V,10%,X7R,A36096-045!!
S!C2L29!!DEFAULT_CAPACITOR_10000pF_2_1!!CAP!!CAP_0402LF-0.01UF,25V,10%,X7R,A36096-045!!
S!C2L36!!DEFAULT_CAPACITOR_10000pF_2_1!!CAP!!CAP_0402LF-0.01UF,25V,10%,X7R,A36096-045!!
S!C2L34!!DEFAULT_CAPACITOR_10000pF_2_1!!CAP!!CAP_0402LF-0.01UF,25V,10%,X7R,A36096-045!!
S!C2L30!!DEFAULT_CAPACITOR_10000pF_2_1!!CAP!!CAP_0402LF-0.01UF,25V,10%,X7R,A36096-045!!
S!C2L28!!DEFAULT_CAPACITOR_10000pF_2_1!!CAP!!CAP_0402LF-0.01UF,25V,10%,X7R,A36096-045!!
S!C2L35!!DEFAULT_CAPACITOR_10000pF_2_1!!CAP!!CAP_0402LF-0.01UF,25V,10%,X7R,A36096-045!!
S!C2L33!!DEFAULT_CAPACITOR_10000pF_2_1!!CAP!!CAP_0402LF-0.01UF,25V,10%,X7R,A36096-045!!
S!C1L12!!DEFAULT_CAPACITOR_10000pF_2_1!!CAP!!CAP_0402LF-0.01UF,25V,10%,X7R,A36096-045!!
S!C1L14!!DEFAULT_CAPACITOR_10000pF_2_1!!CAP!!CAP_0402LF-0.01UF,25V,10%,X7R,A36096-045!!
S!C1L2!!DEFAULT_CAPACITOR_10000pF_2_1!!CAP!!CAP_0402LF-0.01UF,25V,10%,X7R,A36096-045!!
S!C1L6!!DEFAULT_CAPACITOR_10000pF_2_1!!CAP!!CAP_0402LF-0.01UF,25V,10%,X7R,A36096-045!!
S!C1L13!!DEFAULT_CAPACITOR_10000pF_2_1!!CAP!!CAP_0402LF-0.01UF,25V,10%,X7R,A36096-045!!
S!C1L15!!DEFAULT_CAPACITOR_10000pF_2_1!!CAP!!CAP_0402LF-0.01UF,25V,10%,X7R,A36096-045!!
S!C1L3!!DEFAULT_CAPACITOR_10000pF_2_1!!CAP!!CAP_0402LF-0.01UF,25V,10%,X7R,A36096-045!!
S!C1L7!!DEFAULT_CAPACITOR_10000pF_2_1!!CAP!!CAP_0402LF-0.01UF,25V,10%,X7R,A36096-045!!
S!C2L14!!DEFAULT_CAPACITOR_10000pF_2_1!!CAP!!CAP_0402LF-0.01UF,25V,10%,X7R,A36096-045!!
S!C2L5!!DEFAULT_CAPACITOR_10000pF_2_1!!CAP!!CAP_0402LF-0.01UF,25V,10%,X7R,A36096-045!!
S!C2L18!!DEFAULT_CAPACITOR_10000pF_2_1!!CAP!!CAP_0402LF-0.01UF,25V,10%,X7R,A36096-045!!
S!C2L9!!DEFAULT_CAPACITOR_10000pF_2_1!!CAP!!CAP_0402LF-0.01UF,25V,10%,X7R,A36096-045!!
S!C2L20!!DEFAULT_CAPACITOR_10000pF_2_1!!CAP!!CAP_0402LF-0.01UF,25V,10%,X7R,A36096-045!!
S!C2L12!!DEFAULT_CAPACITOR_10000pF_2_1!!CAP!!CAP_0402LF-0.01UF,25V,10%,X7R,A36096-045!!
S!C2L16!!DEFAULT_CAPACITOR_10000pF_2_1!!CAP!!CAP_0402LF-0.01UF,25V,10%,X7R,A36096-045!!
S!C2L7!!DEFAULT_CAPACITOR_10000pF_2_1!!CAP!!CAP_0402LF-0.01UF,25V,10%,X7R,A36096-045!!
S!C2L47!!DEFAULT_CAPACITOR_10000pF_2_1!!CAP!!CAP_0402LF-0.01UF,25V,10%,X7R,A36096-045!!
S!C2L27!!DEFAULT_CAPACITOR_10000pF_2_1!!CAP!!CAP_0402LF-0.01UF,25V,10%,X7R,A36096-045!!
S!C2L48!!DEFAULT_CAPACITOR_10000pF_2_1!!CAP!!CAP_0402LF-0.01UF,25V,10%,X7R,A36096-045!!
S!C2L24!!DEFAULT_CAPACITOR_10000pF_2_1!!CAP!!CAP_0402LF-0.01UF,25V,10%,X7R,A36096-045!!
S!C2L37!!DEFAULT_CAPACITOR_10000pF_2_1!!CAP!!CAP_0402LF-0.01UF,25V,10%,X7R,A36096-045!!
S!C2L26!!DEFAULT_CAPACITOR_10000pF_2_1!!CAP!!CAP_0402LF-0.01UF,25V,10%,X7R,A36096-045!!
S!C2L38!!DEFAULT_CAPACITOR_10000pF_2_1!!CAP!!CAP_0402LF-0.01UF,25V,10%,X7R,A36096-045!!
S!C2L21!!DEFAULT_CAPACITOR_10000pF_2_1!!CAP!!CAP_0402LF-0.01UF,25V,10%,X7R,A36096-045!!
S!C2P8!!DEFAULT_CAPACITOR_10000pF_2_1!!CAP!!CAP_0402LF-0.01UF,25V,10%,X7R,A36096-045!!
S!C4F10!!DEFAULT_CAPACITOR_10000pF_2_1!!CAP!!CAP_0402LF-0.01UF,25V,10%,X7R,A36096-045!!
S!C4G3!!DEFAULT_CAPACITOR_10000pF_2_1!!CAP!!CAP_0402LF-0.01UF,25V,10%,X7R,A36096-045!!
S!C9U7!!DEFAULT_CAPACITOR_10000pF_2_1!!CAP!!CAP_0402LF-0.01UF,25V,10%,X7R,A36096-045!!
S!C1F22!!DEFAULT_CAPACITOR_10000pF_2_1!!CAP!!CAP_0402LF-0.01UF,25V,10%,X7R,A36096-045!!
S!C4G19!!DEFAULT_CAPACITOR_10000pF_2_1!!CAP!!CAP_0402LF-0.01UF,25V,10%,X7R,A36096-045!!
S!C6U17!!DEFAULT_CAPACITOR_10000pF_2_1!!CAP!!CAP_0402LF-0.01UF,25V,10%,X7R,A36096-045!!
S!C4B12!!DEFAULT_CAPACITOR_10000pF_2_1!!CAP!!CAP_0402LF-0.01UF,25V,10%,X7R,A36096-045!!
S!C6L6!!DEFAULT_CAPACITOR_10000pF_2_1!!CAP!!CAP_0402LF-0.01UF,25V,10%,X7R,A36096-045!!
S!C9L1!!DEFAULT_CAPACITOR_10000pF_2_1!!CAP!!CAP_0402LF-0.01UF,25V,10%,X7R,A36096-045!!
S!C1A5!!DEFAULT_CAPACITOR_10000pF_2_1!!CAP!!CAP_0402LF-0.01UF,25V,10%,X7R,A36096-045!!
S!C6L1!!DEFAULT_CAPACITOR_10000pF_2_1!!CAP!!CAP_0402LF-0.01UF,25V,10%,X7R,A36096-045!!
S!C1B9!!DEFAULT_CAPACITOR_10000pF_2_1!!CAP!!CAP_0402LF-0.01UF,25V,10%,X7R,A36096-045!!
S!C4A5!!DEFAULT_CAPACITOR_10000pF_2_1!!CAP!!CAP_0402LF-0.01UF,25V,10%,X7R,A36096-045!!
S!C1G19!!DEFAULT_CAPACITOR_10000pF_2_1!!CAP!!CAP_0402LF-0.01UF,25V,10%,X7R,A36096-045!!
S!C9M1!!DEFAULT_CAPACITOR_10000pF_2_1!!CAP!!CAP_0402LF-0.01UF,25V,10%,X7R,A36096-045!!
S!C1A17!!DEFAULT_CAPACITOR_10000pF_2_1!!CAP!!CAP_0402LF-0.01UF,25V,10%,X7R,A36096-045!!
S!C9T7!!DEFAULT_CAPACITOR_10000pF_2_1!!CAP!!CAP_0402LF-0.01UF,25V,10%,X7R,A36096-045!!
S!C1G10!!DEFAULT_CAPACITOR_10000pF_2_1!!CAP!!CAP_0402LF-0.01UF,25V,10%,X7R,A36096-045!!
S!C4A18!!DEFAULT_CAPACITOR_10000pF_2_1!!CAP!!CAP_0402LF-0.01UF,25V,10%,X7R,A36096-045!!
S!C6T1!!DEFAULT_CAPACITOR_10000pF_2_1!!CAP!!CAP_0402LF-0.01UF,25V,10%,X7R,A36096-045!!
S!C6U9!!DEFAULT_CAPACITOR_10000pF_2_1!!CAP!!CAP_0402LF-0.01UF,25V,10%,X7R,A36096-045!!
S!C6M1!!DEFAULT_CAPACITOR_10000pF_2_1!!CAP!!CAP_0402LF-0.01UF,25V,10%,X7R,A36096-045!!
S!C9U10!!DEFAULT_CAPACITOR_10000pF_2_1!!CAP!!CAP_0402LF-0.01UF,25V,10%,X7R,A36096-045!!
S!C9L7!!DEFAULT_CAPACITOR_10000pF_2_1!!CAP!!CAP_0402LF-0.01UF,25V,10%,X7R,A36096-045!!
S!C8F5!!DEFAULT_CAPACITOR_10000pF_2_1!!CAP!!CAP_0402LF-0.01UF,25V,10%,X7R,A36096-045!!
S!C7F1!!DEFAULT_CAPACITOR_10000pF_2_1!YES!CAP!!CAP_0402LF-0.01UF,25V,10%,X7R,A36096-045!!
S!C3T5!!DEFAULT_CAPACITOR_10000pF_2_1!YES!CAP!!CAP_0402LF-0.01UF,25V,10%,X7R,A36096-045!!
S!C2L17!!DEFAULT_CAPACITOR_10000pF_2_1!!CAP!!CAP_0402LF-0.01UF,25V,10%,X7R,A36096-045!!
S!C2L6!!DEFAULT_CAPACITOR_10000pF_2_1!!CAP!!CAP_0402LF-0.01UF,25V,10%,X7R,A36096-045!!
S!C2L13!!DEFAULT_CAPACITOR_10000pF_2_1!!CAP!!CAP_0402LF-0.01UF,25V,10%,X7R,A36096-045!!
S!C2L3!!DEFAULT_CAPACITOR_10000pF_2_1!!CAP!!CAP_0402LF-0.01UF,25V,10%,X7R,A36096-045!!
S!C2L19!!DEFAULT_CAPACITOR_10000pF_2_1!!CAP!!CAP_0402LF-0.01UF,25V,10%,X7R,A36096-045!!
S!C2L10!!DEFAULT_CAPACITOR_10000pF_2_1!!CAP!!CAP_0402LF-0.01UF,25V,10%,X7R,A36096-045!!
S!C2L15!!DEFAULT_CAPACITOR_10000pF_2_1!!CAP!!CAP_0402LF-0.01UF,25V,10%,X7R,A36096-045!!
S!C2L4!!DEFAULT_CAPACITOR_10000pF_2_1!!CAP!!CAP_0402LF-0.01UF,25V,10%,X7R,A36096-045!!
S!C2L41!!DEFAULT_CAPACITOR_10000pF_2_1!!CAP!!CAP_0402LF-0.01UF,25V,10%,X7R,A36096-045!!
S!C2L23!!DEFAULT_CAPACITOR_10000pF_2_1!!CAP!!CAP_0402LF-0.01UF,25V,10%,X7R,A36096-045!!
S!C2L39!!DEFAULT_CAPACITOR_10000pF_2_1!!CAP!!CAP_0402LF-0.01UF,25V,10%,X7R,A36096-045!!
S!C2L43!!DEFAULT_CAPACITOR_10000pF_2_1!!CAP!!CAP_0402LF-0.01UF,25V,10%,X7R,A36096-045!!
S!C2L42!!DEFAULT_CAPACITOR_10000pF_2_1!!CAP!!CAP_0402LF-0.01UF,25V,10%,X7R,A36096-045!!
S!C2L22!!DEFAULT_CAPACITOR_10000pF_2_1!!CAP!!CAP_0402LF-0.01UF,25V,10%,X7R,A36096-045!!
S!C2L40!!DEFAULT_CAPACITOR_10000pF_2_1!!CAP!!CAP_0402LF-0.01UF,25V,10%,X7R,A36096-045!!
S!C2L44!!DEFAULT_CAPACITOR_10000pF_2_1!!CAP!!CAP_0402LF-0.01UF,25V,10%,X7R,A36096-045!!
S!C1F9!!DEFAULT_CAPACITOR_10000pF_2_1!!CAP!!CAP_0402LF-0.01UF,25V,10%,X7R,A36096-045!!
S!C1B15!4!DEFAULT_CAPACITOR_10000pF_2_1!!CAP!!CAP_0402LF-0.01UF,25V,10%,X7R,A36096-045!!
S!C2T18!!DEFAULT_CAPACITOR_10000pF_2_1!!CAP!!CAP_0402LF-0.01UF,25V,10%,X7R,A36096-045!!
S!C2T37!!DEFAULT_CAPACITOR_10000pF_2_1!!CAP!!CAP_0402LF-0.01UF,25V,10%,X7R,A36096-045!!
S!C2T27!!DEFAULT_CAPACITOR_10000pF_2_1!!CAP!!CAP_0402LF-0.01UF,25V,10%,X7R,A36096-045!!
S!C1G8!!DEFAULT_CAPACITOR_10000pF_2_1!!CAP!!CAP_0402LF-0.01UF,25V,10%,X7R,A36096-045!!
S!C1G18!2!DEFAULT_CAPACITOR_10000pF_2_1!!CAP!!CAP_0402LF-0.01UF,25V,10%,X7R,A36096-045!!
S!C9L8!!DEFAULT_CAPACITOR_10000pF_2_1!!CAP!!CAP_0402LF-0.01UF,25V,10%,X7R,A36096-045!!
S!C9L3!!DEFAULT_CAPACITOR_10000pF_2_1!!CAP!!CAP_0402LF-0.01UF,25V,10%,X7R,A36096-045!!
S!C6L7!!DEFAULT_CAPACITOR_10000pF_2_1!!CAP!!CAP_0402LF-0.01UF,25V,10%,X7R,A36096-045!!
S!C4G1!!DEFAULT_CAPACITOR_10000pF_2_1!!CAP!!CAP_0402LF-0.01UF,25V,10%,X7R,A36096-045!!
S!C4G17!!DEFAULT_CAPACITOR_10000pF_2_1!!CAP!!CAP_0402LF-0.01UF,25V,10%,X7R,A36096-045!!
S!C6L2!!DEFAULT_CAPACITOR_10000pF_2_1!!CAP!!CAP_0402LF-0.01UF,25V,10%,X7R,A36096-045!!
S!C1T39!!DEFAULT_CAPACITOR_10000pF_2_1!!CAP!!CAP_0402LF-0.01UF,25V,10%,X7R,A36096-045!!
S!C1T41!!DEFAULT_CAPACITOR_10000pF_2_1!!CAP!!CAP_0402LF-0.01UF,25V,10%,X7R,A36096-045!!
S!C1T34!!DEFAULT_CAPACITOR_10000pF_2_1!!CAP!!CAP_0402LF-0.01UF,25V,10%,X7R,A36096-045!!
S!C1T24!!DEFAULT_CAPACITOR_10000pF_2_1!!CAP!!CAP_0402LF-0.01UF,25V,10%,X7R,A36096-045!!
S!C1T27!!DEFAULT_CAPACITOR_10000pF_2_1!!CAP!!CAP_0402LF-0.01UF,25V,10%,X7R,A36096-045!!
S!C1T36!!DEFAULT_CAPACITOR_10000pF_2_1!!CAP!!CAP_0402LF-0.01UF,25V,10%,X7R,A36096-045!!
S!C6M2!!DEFAULT_CAPACITOR_10000pF_2_1!!CAP!!CAP_0402LF-0.01UF,25V,10%,X7R,A36096-045!!
S!C4F9!!DEFAULT_CAPACITOR_10000pF_2_1!!CAP!!CAP_0402LF-0.01UF,25V,10%,X7R,A36096-045!!
S!C1M36!!DEFAULT_CAPACITOR_10000pF_2_1!!CAP!!CAP_0402LF-0.01UF,25V,10%,X7R,A36096-045!!
S!C2L52!!DEFAULT_CAPACITOR_10000pF_2_1!!CAP!!CAP_0402LF-0.01UF,25V,10%,X7R,A36096-045!!
S!C2L49!!DEFAULT_CAPACITOR_10000pF_2_1!!CAP!!CAP_0402LF-0.01UF,25V,10%,X7R,A36096-045!!
S!C2L51!!DEFAULT_CAPACITOR_10000pF_2_1!!CAP!!CAP_0402LF-0.01UF,25V,10%,X7R,A36096-045!!
S!C2L50!!DEFAULT_CAPACITOR_10000pF_2_1!!CAP!!CAP_0402LF-0.01UF,25V,10%,X7R,A36096-045!!
S!C1F19!!DEFAULT_CAPACITOR_10000pF_2_1!!CAP!!CAP_0402LF-0.01UF,25V,10%,X7R,A36096-045!!
S!C9M2!!DEFAULT_CAPACITOR_10000pF_2_1!!CAP!!CAP_0402LF-0.01UF,25V,10%,X7R,A36096-045!!
S!C1B16!!DEFAULT_CAPACITOR_100000pF_2_1!!CAP!!CAP_0402LF-0.1UF,16V,10%,EMPTY,A36096-030!!
S!C1T17!!DEFAULT_CAPACITOR_100000pF_2_1!!CAP!!CAP_0402LF-0.1UF,16V,10%,EMPTY,A36096-030!!
S!C4C2!!DEFAULT_CAPACITOR_100000pF_2_1!!CAP!!CAP_0402LF-0.1UF,16V,10%,EMPTY,A36096-030!!
S!C9F15!!DEFAULT_CAPACITOR_100000pF_2_1!!CAP!!CAP_0402LF-0.1UF,16V,10%,EMPTY,A36096-030!!
S!C9F16!!!!CAP!!CAP_0402LF-0.1UF,16V,10%,EMPTY,A36096-030!!
S!C9F17!!!!CAP!!CAP_0402LF-0.1UF,16V,10%,EMPTY,A36096-030!!
S!C2M4!!!!CAP!!CAP_0402LF-0.1UF,16V,10%,EMPTY,A36096-030!!
S!C2M3!!!!CAP!!CAP_0402LF-0.1UF,16V,10%,EMPTY,A36096-030!!
S!C3D27!331!!!CAP!!CAP_0402LF-0.1UF,16V,10%,EMPTY,A36096-030!!
S!C3P1!386!!!CAP!!CAP_0402LF-0.1UF,16V,10%,EMPTY,A36096-030!!
S!C9P12!21!!!CAP!!CAP_0402LF-0.1UF,16V,10%,EMPTY,A36096-030!!
S!C9P17!!!!CAP!!CAP_0402LF-0.1UF,16V,10%,EMPTY,A36096-030!!
S!C9P16!!!!CAP!!CAP_0402LF-0.1UF,16V,10%,EMPTY,A36096-030!!
S!C1D22!!!!CAP!!CAP_0402LF-0.1UF,16V,10%,EMPTY,A36096-030!!
S!C1M33!!!!CAP!!CAP_0402LF-0.1UF,16V,10%,X7R,A36096-030!!
S!C6M6!!!!CAP!!CAP_0402LF-0.1UF,16V,10%,X7R,A36096-030!!
S!C9F23!!!!CAP!!CAP_0402LF-0.1UF,16V,10%,X7R,A36096-030!!
S!C4R2!!!!CAP!!CAP_0402LF-0.1UF,16V,10%,X7R,A36096-030!!
S!C8C8!!DEFAULT_CAPACITOR_100000pF_2_1!!CAP!!CAP_0402LF-0.1UF,16V,10%,X7R,A36096-030!!
S!C8C9!!DEFAULT_CAPACITOR_100000pF_2_1!!CAP!!CAP_0402LF-0.1UF,16V,10%,X7R,A36096-030!!
S!C8C11!!DEFAULT_CAPACITOR_100000pF_2_1!!CAP!!CAP_0402LF-0.1UF,16V,10%,X7R,A36096-030!!
S!C8C10!!DEFAULT_CAPACITOR_100000pF_2_1!!CAP!!CAP_0402LF-0.1UF,16V,10%,X7R,A36096-030!!
S!C8C12!!DEFAULT_CAPACITOR_100000pF_2_1!!CAP!!CAP_0402LF-0.1UF,16V,10%,X7R,A36096-030!!
S!C8C13!!DEFAULT_CAPACITOR_100000pF_2_1!!CAP!!CAP_0402LF-0.1UF,16V,10%,X7R,A36096-030!!
S!C8C15!!DEFAULT_CAPACITOR_100000pF_2_1!!CAP!!CAP_0402LF-0.1UF,16V,10%,X7R,A36096-030!!
S!C8C14!!DEFAULT_CAPACITOR_100000pF_2_1!!CAP!!CAP_0402LF-0.1UF,16V,10%,X7R,A36096-030!!
S!C2P12!!!!CAP!!CAP_0402LF-0.1UF,16V,10%,X7R,A36096-030!!
S!C2P11!!!!CAP!!CAP_0402LF-0.1UF,16V,10%,X7R,A36096-030!!
S!C2R15!!!!CAP!!CAP_0402LF-0.1UF,16V,10%,X7R,A36096-030!!
S!C2P13!!!!CAP!!CAP_0402LF-0.1UF,16V,10%,X7R,A36096-030!!
S!C2P14!!!!CAP!!CAP_0402LF-0.1UF,16V,10%,X7R,A36096-030!!
S!C2P15!!!!CAP!!CAP_0402LF-0.1UF,16V,10%,X7R,A36096-030!!
S!C2P16!!!!CAP!!CAP_0402LF-0.1UF,16V,10%,X7R,A36096-030!!
S!C2R16!!!!CAP!!CAP_0402LF-0.1UF,16V,10%,X7R,A36096-030!!
S!C2R17!!!!CAP!!CAP_0402LF-0.1UF,16V,10%,X7R,A36096-030!!
S!C2R18!!!!CAP!!CAP_0402LF-0.1UF,16V,10%,X7R,A36096-030!!
S!C7D1!!!!CAP!!CAP_0402LF-0.1UF,16V,10%,X7R,A36096-030!!
S!C1D21!!!!CAP!!CAP_0402LF-0.1UF,16V,10%,X7R,A36096-030!!
S!C9U12!!!!CAP!!CAP_0402LF-0.1UF,16V,10%,X7R,A36096-030!!
S!C3L31!!!!CAP!!CAP_0402LF-0.1UF,16V,10%,X7R,A36096-030!!
S!C3U10!!!!CAP!!CAP_0402LF-0.1UF,16V,10%,X7R,A36096-030!!
S!C9M11!!!!CAP!!CAP_0402LF-0.1UF,16V,10%,X7R,A36096-030!!
S!C7E4!!!!CAP!!CAP_0402LF-0.1UF,16V,10%,X7R,A36096-030!!
S!C9F7!!DEFAULT_CAPACITOR_100000pF_2_1!!CAP!!CAP_0402LF-0.1UF,16V,10%,X7R,A36096-030!!
S!C9F11!!DEFAULT_CAPACITOR_100000pF_2_1!!CAP!!CAP_0402LF-0.1UF,16V,10%,X7R,A36096-030!!
S!C8F16!!DEFAULT_CAPACITOR_100000pF_2_1!!CAP!!CAP_0402LF-0.1UF,16V,10%,X7R,A36096-030!!
S!C2T35!!DEFAULT_CAPACITOR_100000pF_2_1!!CAP!!CAP_0402LF-0.1UF,16V,10%,X7R,A36096-030!!
S!C1L11!!DEFAULT_CAPACITOR_100000pF_2_1!!CAP!!CAP_0402LF-0.1UF,16V,10%,X7R,A36096-030!!
S!C8E1!!DEFAULT_CAPACITOR_100000pF_2_1!!CAP!!CAP_0402LF-0.1UF,16V,10%,X7R,A36096-030!!
S!C2T12!!DEFAULT_CAPACITOR_100000pF_2_1!!CAP!!CAP_0402LF-0.1UF,16V,10%,X7R,A36096-030!!
S!C2T8!!DEFAULT_CAPACITOR_100000pF_2_1!!CAP!!CAP_0402LF-0.1UF,16V,10%,X7R,A36096-030!!
S!C8D1!!DEFAULT_CAPACITOR_100000pF_2_1!!CAP!!CAP_0402LF-0.1UF,16V,10%,X7R,A36096-030!!
S!C2T3!!DEFAULT_CAPACITOR_100000pF_2_1!!CAP!!CAP_0402LF-0.1UF,16V,10%,X7R,A36096-030!!
S!C6P9!!DEFAULT_CAPACITOR_100000pF_2_1!!CAP!!CAP_0402LF-0.1UF,16V,10%,X7R,A36096-030!!
S!C2T34!!DEFAULT_CAPACITOR_100000pF_2_1!!CAP!!CAP_0402LF-0.1UF,16V,10%,X7R,A36096-030!!
S!C9P11!!DEFAULT_CAPACITOR_100000pF_2_1!!CAP!!CAP_0402LF-0.1UF,16V,10%,X7R,A36096-030!!
S!C8E8!!DEFAULT_CAPACITOR_100000pF_2_1!!CAP!!CAP_0402LF-0.1UF,16V,10%,X7R,A36096-030!!
S!C1D26!!DEFAULT_CAPACITOR_100000pF_2_1!!CAP!!CAP_0402LF-0.1UF,16V,10%,X7R,A36096-030!!
S!C1D9!!DEFAULT_CAPACITOR_100000pF_2_1!!CAP!!CAP_0402LF-0.1UF,16V,10%,X7R,A36096-030!!
S!C9P6!!DEFAULT_CAPACITOR_100000pF_2_1!!CAP!!CAP_0402LF-0.1UF,16V,10%,X7R,A36096-030!!
S!C9P15!!DEFAULT_CAPACITOR_100000pF_2_1!!CAP!!CAP_0402LF-0.1UF,16V,10%,X7R,A36096-030!!
S!C7B6!!DEFAULT_CAPACITOR_100000pF_2_1!!CAP!!CAP_0402LF-0.1UF,16V,10%,X7R,A36096-030!!
S!C7F6!!DEFAULT_CAPACITOR_100000pF_2_1!!CAP!!CAP_0402LF-0.1UF,16V,10%,X7R,A36096-030!!
S!C6U5!!DEFAULT_CAPACITOR_100000pF_2_1!!CAP!!CAP_0402LF-0.1UF,16V,10%,X7R,A36096-030!!
S!C4A20!!DEFAULT_CAPACITOR_100000pF_2_1!!CAP!!CAP_0402LF-0.1UF,16V,10%,X7R,A36096-030!!
S!C1M29!!DEFAULT_CAPACITOR_100000pF_2_1!!CAP!!CAP_0402LF-0.1UF,16V,10%,X7R,A36096-030!!
S!C1R28!!DEFAULT_CAPACITOR_100000pF_2_1!!CAP!!CAP_0402LF-0.1UF,16V,10%,X7R,A36096-030!!
S!C2P1!!DEFAULT_CAPACITOR_100000pF_2_1!!CAP!!CAP_0402LF-0.1UF,16V,10%,X7R,A36096-030!!
S!C8D2!!DEFAULT_CAPACITOR_100000pF_2_1!!CAP!!CAP_0402LF-0.1UF,16V,10%,X7R,A36096-030!!
S!C1R27!!DEFAULT_CAPACITOR_100000pF_2_1!!CAP!!CAP_0402LF-0.1UF,16V,10%,X7R,A36096-030!!
S!C2T29!!DEFAULT_CAPACITOR_100000pF_2_1!!CAP!!CAP_0402LF-0.1UF,16V,10%,X7R,A36096-030!!
S!C2T24!!DEFAULT_CAPACITOR_100000pF_2_1!!CAP!!CAP_0402LF-0.1UF,16V,10%,X7R,A36096-030!!
S!C2T5!!DEFAULT_CAPACITOR_100000pF_2_1!!CAP!!CAP_0402LF-0.1UF,16V,10%,X7R,A36096-030!!
S!C2T26!!DEFAULT_CAPACITOR_100000pF_2_1!!CAP!!CAP_0402LF-0.1UF,16V,10%,X7R,A36096-030!!
S!C2T15!!DEFAULT_CAPACITOR_100000pF_2_1!!CAP!!CAP_0402LF-0.1UF,16V,10%,X7R,A36096-030!!
S!C2T4!!DEFAULT_CAPACITOR_100000pF_2_1!!CAP!!CAP_0402LF-0.1UF,16V,10%,X7R,A36096-030!!
S!C2T21!!DEFAULT_CAPACITOR_100000pF_2_1!!CAP!!CAP_0402LF-0.1UF,16V,10%,X7R,A36096-030!!
S!C2T16!!DEFAULT_CAPACITOR_100000pF_2_1!!CAP!!CAP_0402LF-0.1UF,16V,10%,X7R,A36096-030!!
S!C2T2!!DEFAULT_CAPACITOR_100000pF_2_1!!CAP!!CAP_0402LF-0.1UF,16V,10%,X7R,A36096-030!!
S!C9F19!!DEFAULT_CAPACITOR_100000pF_2_1!!CAP!!CAP_0402LF-0.1UF,16V,10%,X7R,A36096-030!!
S!C2U22!!DEFAULT_CAPACITOR_100000pF_2_1!!CAP!!CAP_0402LF-0.1UF,16V,10%,X7R,A36096-030!!
S!C2U23!!DEFAULT_CAPACITOR_100000pF_2_1!!CAP!!CAP_0402LF-0.1UF,16V,10%,X7R,A36096-030!!
S!C9F5!!DEFAULT_CAPACITOR_100000pF_2_1!!CAP!!CAP_0402LF-0.1UF,16V,10%,X7R,A36096-030!!
S!C9A1!!DEFAULT_CAPACITOR_100000pF_2_1!!CAP!!CAP_0402LF-0.1UF,16V,10%,X7R,A36096-030!!
S!C8E2!!DEFAULT_CAPACITOR_100000pF_2_1!!CAP!!CAP_0402LF-0.1UF,16V,10%,X7R,A36096-030!!
S!C3F2!!DEFAULT_CAPACITOR_100000pF_2_1!!CAP!!CAP_0402LF-0.1UF,16V,10%,X7R,A36096-030!!
S!C6F1!!DEFAULT_CAPACITOR_100000pF_2_1!!CAP!!CAP_0402LF-0.1UF,16V,10%,X7R,A36096-030!!
S!C2P7!!DEFAULT_CAPACITOR_100000pF_2_1!!CAP!!CAP_0402LF-0.1UF,16V,10%,X7R,A36096-030!!
S!C2R3!!DEFAULT_CAPACITOR_100000pF_2_1!!CAP!!CAP_0402LF-0.1UF,16V,10%,X7R,A36096-030!!
S!C3P47!!DEFAULT_CAPACITOR_100000pF_2_1!!CAP!!CAP_0402LF-0.1UF,16V,10%,X7R,A36096-030!!
S!C3P52!!DEFAULT_CAPACITOR_100000pF_2_1!!CAP!!CAP_0402LF-0.1UF,16V,10%,X7R,A36096-030!!
S!C3P51!!DEFAULT_CAPACITOR_100000pF_2_1!!CAP!!CAP_0402LF-0.1UF,16V,10%,X7R,A36096-030!!
S!C2P6!!DEFAULT_CAPACITOR_100000pF_2_1!!CAP!!CAP_0402LF-0.1UF,16V,10%,X7R,A36096-030!!
S!C2R5!!DEFAULT_CAPACITOR_100000pF_2_1!!CAP!!CAP_0402LF-0.1UF,16V,10%,X7R,A36096-030!!
S!C3R3!!DEFAULT_CAPACITOR_100000pF_2_1!!CAP!!CAP_0402LF-0.1UF,16V,10%,X7R,A36096-030!!
S!C2R1!!DEFAULT_CAPACITOR_100000pF_2_1!!CAP!!CAP_0402LF-0.1UF,16V,10%,X7R,A36096-030!!
S!C3P43!!DEFAULT_CAPACITOR_100000pF_2_1!!CAP!!CAP_0402LF-0.1UF,16V,10%,X7R,A36096-030!!
S!C2P5!!DEFAULT_CAPACITOR_100000pF_2_1!!CAP!!CAP_0402LF-0.1UF,16V,10%,X7R,A36096-030!!
S!C2P4!!DEFAULT_CAPACITOR_100000pF_2_1!!CAP!!CAP_0402LF-0.1UF,16V,10%,X7R,A36096-030!!
S!C2P2!!DEFAULT_CAPACITOR_100000pF_2_1!!CAP!!CAP_0402LF-0.1UF,16V,10%,X7R,A36096-030!!
S!C3R1!!DEFAULT_CAPACITOR_100000pF_2_1!!CAP!!CAP_0402LF-0.1UF,16V,10%,X7R,A36096-030!!
S!C3R2!!DEFAULT_CAPACITOR_100000pF_2_1!!CAP!!CAP_0402LF-0.1UF,16V,10%,X7R,A36096-030!!
S!C2R4!!DEFAULT_CAPACITOR_100000pF_2_1!!CAP!!CAP_0402LF-0.1UF,16V,10%,X7R,A36096-030!!
S!C2R2!!DEFAULT_CAPACITOR_100000pF_2_1!!CAP!!CAP_0402LF-0.1UF,16V,10%,X7R,A36096-030!!
S!C2P3!!DEFAULT_CAPACITOR_100000pF_2_1!!CAP!!CAP_0402LF-0.1UF,16V,10%,X7R,A36096-030!!
S!C3P44!!DEFAULT_CAPACITOR_100000pF_2_1!!CAP!!CAP_0402LF-0.1UF,16V,10%,X7R,A36096-030!!
S!C3P48!!DEFAULT_CAPACITOR_100000pF_2_1!!CAP!!CAP_0402LF-0.1UF,16V,10%,X7R,A36096-030!!
S!C4D22!!DEFAULT_CAPACITOR_100000pF_2_1!!CAP!!CAP_0402LF-0.1UF,16V,10%,X7R,A36096-030!!
S!C4D24!!DEFAULT_CAPACITOR_100000pF_2_1!!CAP!!CAP_0402LF-0.1UF,16V,10%,X7R,A36096-030!!
S!C6P4!!DEFAULT_CAPACITOR_100000pF_2_1!!CAP!!CAP_0402LF-0.1UF,16V,10%,X7R,A36096-030!!
S!C6P6!!DEFAULT_CAPACITOR_100000pF_2_1!!CAP!!CAP_0402LF-0.1UF,16V,10%,X7R,A36096-030!!
S!C6P10!!DEFAULT_CAPACITOR_100000pF_2_1!!CAP!!CAP_0402LF-0.1UF,16V,10%,X7R,A36096-030!!
S!C6P5!!DEFAULT_CAPACITOR_100000pF_2_1!!CAP!!CAP_0402LF-0.1UF,16V,10%,X7R,A36096-030!!
S!C6P12!!DEFAULT_CAPACITOR_100000pF_2_1!!CAP!!CAP_0402LF-0.1UF,16V,10%,X7R,A36096-030!!
S!C6P11!!DEFAULT_CAPACITOR_100000pF_2_1!!CAP!!CAP_0402LF-0.1UF,16V,10%,X7R,A36096-030!!
S!C9A3!!DEFAULT_CAPACITOR_100000pF_2_1!!CAP!!CAP_0402LF-0.1UF,16V,10%,X7R,A36096-030!!
S!C1L9!!DEFAULT_CAPACITOR_100000pF_2_1!!CAP!!CAP_0402LF-0.1UF,16V,10%,X7R,A36096-030!!
S!C1L17!!DEFAULT_CAPACITOR_100000pF_2_1!!CAP!!CAP_0402LF-0.1UF,16V,10%,X7R,A36096-030!!
S!C1L4!!DEFAULT_CAPACITOR_100000pF_2_1!!CAP!!CAP_0402LF-0.1UF,16V,10%,X7R,A36096-030!!
S!C9M6!7!DEFAULT_CAPACITOR_100000pF_2_1!!CAP!!CAP_0402LF-0.1UF,16V,10%,X7R,A36096-030!!
S!C9M9!4!DEFAULT_CAPACITOR_100000pF_2_1!!CAP!!CAP_0402LF-0.1UF,16V,10%,X7R,A36096-030!!
S!C1B19!3!DEFAULT_CAPACITOR_100000pF_2_1!!CAP!!CAP_0402LF-0.1UF,16V,10%,X7R,A36096-030!!
S!C2L11!!DEFAULT_CAPACITOR_100000pF_2_1!!CAP!!CAP_0402LF-0.1UF,16V,10%,X7R,A36096-030!!
S!C8E18!!DEFAULT_CAPACITOR_100000pF_2_1!!CAP!!CAP_0402LF-0.1UF,16V,10%,X7R,A36096-030!!
S!C1T10!!DEFAULT_CAPACITOR_100000pF_2_1!!CAP!!CAP_0402LF-0.1UF,16V,10%,X7R,A36096-030!!
S!C1E22!!DEFAULT_CAPACITOR_100000pF_2_1!!CAP!!CAP_0402LF-0.1UF,16V,10%,X7R,A36096-030!!
S!C2P9!!DEFAULT_CAPACITOR_100000pF_2_1!!CAP!!CAP_0402LF-0.1UF,16V,10%,X7R,A36096-030!!
S!C7E3!!DEFAULT_CAPACITOR_100000pF_2_1!!CAP!!CAP_0402LF-0.1UF,16V,10%,X7R,A36096-030!!
S!C8A8!!DEFAULT_CAPACITOR_100000pF_2_1!!CAP!!CAP_0402LF-0.1UF,16V,10%,X7R,A36096-030!!
S!C7A40!17!DEFAULT_CAPACITOR_100000pF_2_1!!CAP!!CAP_0402LF-0.1UF,16V,10%,X7R,A36096-030!!
S!C7A39!!DEFAULT_CAPACITOR_100000pF_2_1!!CAP!!CAP_0402LF-0.1UF,16V,10%,X7R,A36096-030!!
S!C2T1!!DEFAULT_CAPACITOR_100000pF_2_1!!CAP!!CAP_0402LF-0.1UF,16V,10%,X7R,A36096-030!!
S!C8E5!!DEFAULT_CAPACITOR_100000pF_2_1!!CAP!!CAP_0402LF-0.1UF,16V,10%,X7R,A36096-030!!
S!C1U22!!DEFAULT_CAPACITOR_100000pF_2_1!!CAP!!CAP_0402LF-0.1UF,16V,10%,X7R,A36096-030!!
S!C3P5!417!DEFAULT_CAPACITOR_100000pF_2_1!!CAP!!CAP_0402LF-0.1UF,16V,10%,X7R,A36096-030!!
S!C7C11!420!DEFAULT_CAPACITOR_100000pF_2_1!!CAP!!CAP_0402LF-0.1UF,16V,10%,X7R,A36096-030!!
S!C4D32!355!DEFAULT_CAPACITOR_100000pF_2_1!!CAP!!CAP_0402LF-0.1UF,16V,10%,X7R,A36096-030!!
S!C4E13!362!DEFAULT_CAPACITOR_100000pF_2_1!!CAP!!CAP_0402LF-0.1UF,16V,10%,X7R,A36096-030!!
S!C3P7!414!DEFAULT_CAPACITOR_100000pF_2_1!!CAP!!CAP_0402LF-0.1UF,16V,10%,X7R,A36096-030!!
S!C4D38!344!DEFAULT_CAPACITOR_100000pF_2_1!!CAP!!CAP_0402LF-0.1UF,16V,10%,X7R,A36096-030!!
S!C2U27!!DEFAULT_CAPACITOR_100000pF_2_1!!CAP!!CAP_0402LF-0.1UF,16V,10%,X7R,A36096-030!!
S!C2U28!3!DEFAULT_CAPACITOR_100000pF_2_1!!CAP!!CAP_0402LF-0.1UF,16V,10%,X7R,A36096-030!!
S!C9G19!!DEFAULT_CAPACITOR_100000pF_2_1!!CAP!!CAP_0402LF-0.1UF,16V,10%,X7R,A36096-030!!
S!C4D35!!DEFAULT_CAPACITOR_100000pF_2_1!!CAP!!CAP_0402LF-0.1UF,16V,10%,X7R,A36096-030!!
S!C4D11!!DEFAULT_CAPACITOR_100000pF_2_1!!CAP!!CAP_0402LF-0.1UF,16V,10%,X7R,A36096-030!!
S!C1U10!!DEFAULT_CAPACITOR_1e+07pF_2_1!!CAP!!CAP_0402LF-0.1UF,16V,10%,X7R,A36096-030!!
S!C1U14!!DEFAULT_CAPACITOR_100000pF_2_1!!CAP!!CAP_0402LF-0.1UF,16V,10%,X7R,A36096-030!!
S!C1T54!!DEFAULT_CAPACITOR_100000pF_2_1!!CAP!!CAP_0402LF-0.1UF,16V,10%,X7R,A36096-030!!
S!C1T53!!DEFAULT_CAPACITOR_100000pF_2_1!!CAP!!CAP_0402LF-0.1UF,16V,10%,X7R,A36096-030!!
S!C1U16!!DEFAULT_CAPACITOR_100000pF_2_1!!CAP!!CAP_0402LF-0.1UF,16V,10%,X7R,A36096-030!!
S!C1T33!!DEFAULT_CAPACITOR_100000pF_2_1!!CAP!!CAP_0402LF-0.1UF,16V,10%,X7R,A36096-030!!
S!C1T40!!DEFAULT_CAPACITOR_100000pF_2_1!!CAP!!CAP_0402LF-0.1UF,16V,10%,X7R,A36096-030!!
S!C1U13!!DEFAULT_CAPACITOR_100000pF_2_1!!CAP!!CAP_0402LF-0.1UF,16V,10%,X7R,A36096-030!!
S!C1U15!!DEFAULT_CAPACITOR_100000pF_2_1!!CAP!!CAP_0402LF-0.1UF,16V,10%,X7R,A36096-030!!
S!C1T48!!DEFAULT_CAPACITOR_100000pF_2_1!!CAP!!CAP_0402LF-0.1UF,16V,10%,X7R,A36096-030!!
S!C1E20!!DEFAULT_CAPACITOR_100000pF_2_1!!CAP!!CAP_0402LF-0.1UF,16V,10%,X7R,A36096-030!!
S!C9M5!8!DEFAULT_CAPACITOR_100000pF_2_1!!CAP!!CAP_0402LF-0.1UF,16V,10%,X7R,A36096-030!!
S!C7E5!7!DEFAULT_CAPACITOR_100000pF_2_1!!CAP!!CAP_0402LF-0.1UF,16V,10%,X7R,A36096-030!!
S!C7E9!5!DEFAULT_CAPACITOR_100000pF_2_1!!CAP!!CAP_0402LF-0.1UF,16V,10%,X7R,A36096-030!!
S!C2T36!!DEFAULT_CAPACITOR_100000pF_2_1!!CAP!!CAP_0402LF-0.1UF,16V,10%,X7R,A36096-030!!
S!C2U19!!DEFAULT_CAPACITOR_100000pF_2_1!!CAP!!CAP_0402LF-0.1UF,16V,10%,X7R,A36096-030!!
S!C8B5!!DEFAULT_CAPACITOR_100000pF_2_1!!CAP!!CAP_0402LF-0.1UF,16V,10%,X7R,A36096-030!!
S!C8B7!!DEFAULT_CAPACITOR_100000pF_2_1!!CAP!!CAP_0402LF-0.1UF,16V,10%,X7R,A36096-030!!
S!C8F17!!DEFAULT_CAPACITOR_100000pF_2_1!!CAP!!CAP_0402LF-0.1UF,16V,10%,X7R,A36096-030!!
S!C8E19!1!DEFAULT_CAPACITOR_100000pF_2_1!!CAP!!CAP_0402LF-0.1UF,16V,10%,X7R,A36096-030!!
S!C8B8!!DEFAULT_CAPACITOR_100000pF_2_1!!CAP!!CAP_0402LF-0.1UF,16V,10%,X7R,A36096-030!!
S!C3N29!!DEFAULT_CAPACITOR_100000pF_2_1!!CAP!!CAP_0402LF-0.1UF,16V,10%,X7R,A36096-030!!
S!C1T23!!DEFAULT_CAPACITOR_100000pF_2_1!!CAP!!CAP_0402LF-0.1UF,16V,10%,X7R,A36096-030!!
S!C1T11!!DEFAULT_CAPACITOR_100000pF_2_1!!CAP!!CAP_0402LF-0.1UF,16V,10%,X7R,A36096-030!!
S!C1M38!!DEFAULT_CAPACITOR_100000pF_2_1!!CAP!!CAP_0402LF-0.1UF,16V,10%,X7R,A36096-030!!
S!C9G6!!DEFAULT_CAPACITOR_100000pF_2_1!!CAP!!CAP_0402LF-0.1UF,16V,10%,X7R,A36096-030!!
S!C9G4!!DEFAULT_CAPACITOR_100000pF_2_1!!CAP!!CAP_0402LF-0.1UF,16V,10%,X7R,A36096-030!!
S!C9G7!!DEFAULT_CAPACITOR_100000pF_2_1!!CAP!!CAP_0402LF-0.1UF,16V,10%,X7R,A36096-030!!
S!C9B7!!DEFAULT_CAPACITOR_100000pF_2_1!!CAP!!CAP_0402LF-0.1UF,16V,10%,X7R,A36096-030!!
S!C9R14!!DEFAULT_CAPACITOR_100000pF_2_1!!CAP!!CAP_0402LF-0.1UF,16V,10%,X7R,A36096-030!!
S!C9R13!!DEFAULT_CAPACITOR_100000pF_2_1!!CAP!!CAP_0402LF-0.1UF,16V,10%,X7R,A36096-030!!
S!C7A38!!DEFAULT_CAPACITOR_100000pF_2_1!!CAP!!CAP_0402LF-0.1UF,16V,10%,X7R,A36096-030!!
S!C7B2!!DEFAULT_CAPACITOR_100000pF_2_1!!CAP!!CAP_0402LF-0.1UF,16V,10%,X7R,A36096-030!!
S!C1G25!24!DEFAULT_CAPACITOR_100000pF_2_1!!CAP!!CAP_0402LF-0.1UF,16V,10%,X7R,A36096-030!!
S!C1G22!25!DEFAULT_CAPACITOR_100000pF_2_1!!CAP!!CAP_0402LF-0.1UF,16V,10%,X7R,A36096-030!!
S!C1B5!121!DEFAULT_CAPACITOR_100000pF_2_1!!CAP!!CAP_0402LF-0.1UF,16V,10%,X7R,A36096-030!!
S!C1B2!106!DEFAULT_CAPACITOR_100000pF_2_1!!CAP!!CAP_0402LF-0.1UF,16V,10%,X7R,A36096-030!!
S!C2M24!!DEFAULT_CAPACITOR_100000pF_2_1!!CAP!!CAP_0402LF-0.1UF,16V,10%,X7R,A36096-030!!
S!C2M23!!DEFAULT_CAPACITOR_100000pF_2_1!!CAP!!CAP_0402LF-0.1UF,16V,10%,X7R,A36096-030!!
S!C9E4!!DEFAULT_CAPACITOR_100000pF_2_1!!CAP!!CAP_0402LF-0.1UF,16V,10%,X7R,A36096-030!!
S!C9E5!!DEFAULT_CAPACITOR_100000pF_2_1!!CAP!!CAP_0402LF-0.1UF,16V,10%,X7R,A36096-030!!
S!C1C25!!DEFAULT_CAPACITOR_100000pF_2_1!!CAP!!CAP_0402LF-0.1UF,16V,10%,X7R,A36096-030!!
S!C2T32!!DEFAULT_CAPACITOR_100000pF_2_1!!CAP!!CAP_0402LF-0.1UF,16V,10%,X7R,A36096-030!!
S!C2T17!!DEFAULT_CAPACITOR_100000pF_2_1!!CAP!!CAP_0402LF-0.1UF,16V,10%,X7R,A36096-030!!
S!C2T25!!DEFAULT_CAPACITOR_100000pF_2_1!!CAP!!CAP_0402LF-0.1UF,16V,10%,X7R,A36096-030!!
S!C2T30!!DEFAULT_CAPACITOR_100000pF_2_1!!CAP!!CAP_0402LF-0.1UF,16V,10%,X7R,A36096-030!!
S!C1R25!!DEFAULT_CAPACITOR_100000pF_2_1!!CAP!!CAP_0402LF-0.1UF,16V,10%,X7R,A36096-030!!
S!C1R20!!DEFAULT_CAPACITOR_100000pF_2_1!!CAP!!CAP_0402LF-0.1UF,16V,10%,X7R,A36096-030!!
S!C1T3!!DEFAULT_CAPACITOR_100000pF_2_1!!CAP!!CAP_0402LF-0.1UF,16V,10%,X7R,A36096-030!!
S!C1R14!!DEFAULT_CAPACITOR_100000pF_2_1!!CAP!!CAP_0402LF-0.1UF,16V,10%,X7R,A36096-030!!
S!C1R21!!DEFAULT_CAPACITOR_100000pF_2_1!!CAP!!CAP_0402LF-0.1UF,16V,10%,X7R,A36096-030!!
S!C1R31!!DEFAULT_CAPACITOR_100000pF_2_1!!CAP!!CAP_0402LF-0.1UF,16V,10%,X7R,A36096-030!!
S!C1R19!!DEFAULT_CAPACITOR_100000pF_2_1!!CAP!!CAP_0402LF-0.1UF,16V,10%,X7R,A36096-030!!
S!C1R29!!DEFAULT_CAPACITOR_100000pF_2_1!!CAP!!CAP_0402LF-0.1UF,16V,10%,X7R,A36096-030!!
S!C1R26!!DEFAULT_CAPACITOR_100000pF_2_1!!CAP!!CAP_0402LF-0.1UF,16V,10%,X7R,A36096-030!!
S!C1R15!!DEFAULT_CAPACITOR_100000pF_2_1!!CAP!!CAP_0402LF-0.1UF,16V,10%,X7R,A36096-030!!
S!C1R24!!DEFAULT_CAPACITOR_100000pF_2_1!!CAP!!CAP_0402LF-0.1UF,16V,10%,X7R,A36096-030!!
S!C1T5!!DEFAULT_CAPACITOR_100000pF_2_1!!CAP!!CAP_0402LF-0.1UF,16V,10%,X7R,A36096-030!!
S!C1R18!!DEFAULT_CAPACITOR_100000pF_2_1!!CAP!!CAP_0402LF-0.1UF,16V,10%,X7R,A36096-030!!
S!C1M2!!DEFAULT_CAPACITOR_100000pF_2_1!!CAP!!CAP_0402LF-0.1UF,16V,10%,X7R,A36096-030!!
S!C1M1!!DEFAULT_CAPACITOR_100000pF_2_1!!CAP!!CAP_0402LF-0.1UF,16V,10%,X7R,A36096-030!!
S!C1M20!!DEFAULT_CAPACITOR_100000pF_2_1!!CAP!!CAP_0402LF-0.1UF,16V,10%,X7R,A36096-030!!
S!C9F14!!DEFAULT_CAPACITOR_100000pF_2_1!!CAP!!CAP_0402LF-0.1UF,16V,10%,X7R,A36096-030!!
S!C4G25!!DEFAULT_CAPACITOR_100000pF_2_1!!CAP!!CAP_0402LF-0.1UF,16V,10%,X7R,A36096-030!!
S!C3B4!!DEFAULT_CAPACITOR_100000pF_2_1!!CAP!!CAP_0402LF-0.1UF,16V,10%,X7R,A36096-030!!
S!C3B5!!DEFAULT_CAPACITOR_100000pF_2_1!!CAP!!CAP_0402LF-0.1UF,16V,10%,X7R,A36096-030!!
S!C9A4!!DEFAULT_CAPACITOR_100000pF_2_1!!CAP!!CAP_0402LF-0.1UF,16V,10%,X7R,A36096-030!!
S!C9A2!!DEFAULT_CAPACITOR_100000pF_2_1!!CAP!!CAP_0402LF-0.1UF,16V,10%,X7R,A36096-030!!
S!C9A5!!DEFAULT_CAPACITOR_100000pF_2_1!!CAP!!CAP_0402LF-0.1UF,16V,10%,X7R,A36096-030!!
S!C1L8!!DEFAULT_CAPACITOR_100000pF_2_1!!CAP!!CAP_0402LF-0.1UF,16V,10%,X7R,A36096-030!!
S!C2U21!!DEFAULT_CAPACITOR_100000pF_2_1!!CAP!!CAP_0402LF-0.1UF,16V,10%,X7R,A36096-030!!
S!C2U20!!DEFAULT_CAPACITOR_100000pF_2_1!!CAP!!CAP_0402LF-0.1UF,16V,10%,X7R,A36096-030!!
S!C2U25!!DEFAULT_CAPACITOR_100000pF_2_1!!CAP!!CAP_0402LF-0.1UF,16V,10%,X7R,A36096-030!!
S!C2U24!!DEFAULT_CAPACITOR_100000pF_2_1!!CAP!!CAP_0402LF-0.1UF,16V,10%,X7R,A36096-030!!
S!C1T52!!DEFAULT_CAPACITOR_100000pF_2_1!!CAP!!CAP_0402LF-0.1UF,16V,10%,X7R,A36096-030!!
S!C1U3!!DEFAULT_CAPACITOR_100000pF_2_1!!CAP!!CAP_0402LF-0.1UF,16V,10%,X7R,A36096-030!!
S!C1T29!!DEFAULT_CAPACITOR_100000pF_2_1!!CAP!!CAP_0402LF-0.1UF,16V,10%,X7R,A36096-030!!
S!C1T30!!DEFAULT_CAPACITOR_100000pF_2_1!!CAP!!CAP_0402LF-0.1UF,16V,10%,X7R,A36096-030!!
S!C1T43!!DEFAULT_CAPACITOR_100000pF_2_1!!CAP!!CAP_0402LF-0.1UF,16V,10%,X7R,A36096-030!!
S!C1T45!!DEFAULT_CAPACITOR_100000pF_2_1!!CAP!!CAP_0402LF-0.1UF,16V,10%,X7R,A36096-030!!
S!C1U4!!DEFAULT_CAPACITOR_100000pF_2_1!!CAP!!CAP_0402LF-0.1UF,16V,10%,X7R,A36096-030!!
S!C1T47!!DEFAULT_CAPACITOR_100000pF_2_1!!CAP!!CAP_0402LF-0.1UF,16V,10%,X7R,A36096-030!!
S!C1U11!!DEFAULT_CAPACITOR_100000pF_2_1!!CAP!!CAP_0402LF-0.1UF,16V,10%,X7R,A36096-030!!
S!C1U9!!DEFAULT_CAPACITOR_100000pF_2_1!!CAP!!CAP_0402LF-0.1UF,16V,10%,X7R,A36096-030!!
S!C1T22!!DEFAULT_CAPACITOR_100000pF_2_1!!CAP!!CAP_0402LF-0.1UF,16V,10%,X7R,A36096-030!!
S!C1T50!!DEFAULT_CAPACITOR_100000pF_2_1!!CAP!!CAP_0402LF-0.1UF,16V,10%,X7R,A36096-030!!
S!C1T8!!DEFAULT_CAPACITOR_100000pF_2_1!!CAP!!CAP_0402LF-0.1UF,16V,10%,X7R,A36096-030!!
S!C1T25!!DEFAULT_CAPACITOR_100000pF_2_1!!CAP!!CAP_0402LF-0.1UF,16V,10%,X7R,A36096-030!!
S!C1T14!!DEFAULT_CAPACITOR_100000pF_2_1!!CAP!!CAP_0402LF-0.1UF,16V,10%,X7R,A36096-030!!
S!C1T26!!DEFAULT_CAPACITOR_100000pF_2_1!!CAP!!CAP_0402LF-0.1UF,16V,10%,X7R,A36096-030!!
S!C4D49!26!DEFAULT_CAPACITOR_100000pF_2_1!!CAP!!CAP_0402LF-0.1UF,16V,10%,X7R,A36096-030!!
S!C4E20!12!DEFAULT_CAPACITOR_100000pF_2_1!!CAP!!CAP_0402LF-0.1UF,16V,10%,X7R,A36096-030!!
S!C7G29!63!DEFAULT_CAPACITOR_100000pF_2_1!!CAP!!CAP_0402LF-0.1UF,16V,10%,X7R,A36096-030!!
S!C7G36!32!DEFAULT_CAPACITOR_100000pF_2_1!!CAP!!CAP_0402LF-0.1UF,16V,10%,X7R,A36096-030!!
S!C4C10!81!DEFAULT_CAPACITOR_100000pF_2_1!!CAP!!CAP_0402LF-0.1UF,16V,10%,X7R,A36096-030!!
S!C7F17!43!DEFAULT_CAPACITOR_100000pF_2_1!!CAP!!CAP_0402LF-0.1UF,16V,10%,X7R,A36096-030!!
S!C7F15!77!DEFAULT_CAPACITOR_100000pF_2_1!!CAP!!CAP_0402LF-0.1UF,16V,10%,X7R,A36096-030!!
S!C7A5!26!DEFAULT_CAPACITOR_100000pF_2_1!!CAP!!CAP_0402LF-0.1UF,16V,10%,X7R,A36096-030!!
S!C7A20!15!DEFAULT_CAPACITOR_100000pF_2_1!!CAP!!CAP_0402LF-0.1UF,16V,10%,X7R,A36096-030!!
S!C1A10!68!DEFAULT_CAPACITOR_100000pF_2_1!!CAP!!CAP_0402LF-0.1UF,16V,10%,X7R,A36096-030!!
S!C1A20!73!DEFAULT_CAPACITOR_100000pF_2_1!!CAP!!CAP_0402LF-0.1UF,16V,10%,X7R,A36096-030!!
S!C1G14!20!DEFAULT_CAPACITOR_100000pF_2_1!!CAP!!CAP_0402LF-0.1UF,16V,10%,X7R,A36096-030!!
S!C1F28!27!DEFAULT_CAPACITOR_100000pF_2_1!!CAP!!CAP_0402LF-0.1UF,16V,10%,X7R,A36096-030!!
S!C4D19!33!DEFAULT_CAPACITOR_100000pF_2_1!!CAP!!CAP_0402LF-0.1UF,16V,10%,X7R,A36096-030!!
S!C4D26!42!DEFAULT_CAPACITOR_100000pF_2_1!!CAP!!CAP_0402LF-0.1UF,16V,10%,X7R,A36096-030!!
S!C1C9!!DEFAULT_CAPACITOR_100000pF_2_1!!CAP!!CAP_0402LF-0.1UF,16V,10%,X7R,A36096-030!!
S!C1C14!!DEFAULT_CAPACITOR_100000pF_2_1!!CAP!!CAP_0402LF-0.1UF,16V,10%,X7R,A36096-030!!
S!C1M24!!DEFAULT_CAPACITOR_100000pF_2_1!!CAP!!CAP_0402LF-0.1UF,16V,10%,X7R,A36096-030!!
S!C1M23!!DEFAULT_CAPACITOR_100000pF_2_1!!CAP!!CAP_0402LF-0.1UF,16V,10%,X7R,A36096-030!!
S!C1M22!!DEFAULT_CAPACITOR_100000pF_2_1!!CAP!!CAP_0402LF-0.1UF,16V,10%,X7R,A36096-030!!
S!C1D27!16!DEFAULT_CAPACITOR_100000pF_2_1!!CAP!!CAP_0402LF-0.1UF,16V,10%,X7R,A36096-030!!
S!C1E14!!DEFAULT_CAPACITOR_100000pF_2_1!!CAP!!CAP_0402LF-0.1UF,16V,10%,X7R,A36096-030!!
S!C1D34!!DEFAULT_CAPACITOR_100000pF_2_1!!CAP!!CAP_0402LF-0.1UF,16V,10%,X7R,A36096-030!!
S!C1D28!10!DEFAULT_CAPACITOR_100000pF_2_1!!CAP!!CAP_0402LF-0.1UF,16V,10%,X7R,A36096-030!!
S!C1D13!!DEFAULT_CAPACITOR_100000pF_2_1!!CAP!!CAP_0402LF-0.1UF,16V,10%,X7R,A36096-030!!
S!C1C17!!DEFAULT_CAPACITOR_100000pF_2_1!!CAP!!CAP_0402LF-0.1UF,16V,10%,X7R,A36096-030!!
S!C6F3!8!DEFAULT_CAPACITOR_100000pF_2_1!!CAP!!CAP_0402LF-0.1UF,16V,10%,X7R,A36096-030!!
S!C7E2!!DEFAULT_CAPACITOR_100000pF_2_1!!CAP!!CAP_0402LF-0.1UF,16V,10%,X7R,A36096-030!!
S!C6F2!9!DEFAULT_CAPACITOR_100000pF_2_1!!CAP!!CAP_0402LF-0.1UF,16V,10%,X7R,A36096-030!!
S!C7E1!!DEFAULT_CAPACITOR_100000pF_2_1!!CAP!!CAP_0402LF-0.1UF,16V,10%,X7R,A36096-030!!
S!C4G22!!DEFAULT_CAPACITOR_100000pF_2_1!!CAP!!CAP_0402LF-0.1UF,16V,10%,X7R,A36096-030!!
S!C1D11!29!DEFAULT_CAPACITOR_100000pF_2_1!!CAP!!CAP_0402LF-0.1UF,16V,10%,X7R,A36096-030!!
S!C4C19!40!DEFAULT_CAPACITOR_100000pF_2_1!!CAP!!CAP_0402LF-0.1UF,16V,10%,X7R,A36096-030!!
S!C9R12!!DEFAULT_CAPACITOR_100000pF_2_1!!CAP!!CAP_0402LF-0.1UF,16V,10%,X7R,A36096-030!!
S!C9R6!!DEFAULT_CAPACITOR_100000pF_2_1!!CAP!!CAP_0402LF-0.1UF,16V,10%,X7R,A36096-030!!
S!C1E17!!DEFAULT_CAPACITOR_100000pF_2_1!!CAP!!CAP_0402LF-0.1UF,16V,10%,X7R,A36096-030!!
S!C1E16!!DEFAULT_CAPACITOR_100000pF_2_1!!CAP!!CAP_0402LF-0.1UF,16V,10%,X7R,A36096-030!!
S!C1U5!!DEFAULT_CAPACITOR_100000pF_2_1!!CAP!!CAP_0402LF-0.1UF,16V,10%,X7R,A36096-030!!
S!C1T38!!DEFAULT_CAPACITOR_100000pF_2_1!!CAP!!CAP_0402LF-0.1UF,16V,10%,X7R,A36096-030!!
S!C3P49!19!DEFAULT_CAPACITOR_100000pF_2_1!!CAP!!CAP_0402LF-0.1UF,16V,10%,X7R,A36096-030!!
S!C7D5!5!DEFAULT_CAPACITOR_100000pF_2_1!!CAP!!CAP_0402LF-0.1UF,16V,10%,X7R,A36096-030!!
S!C1T37!!DEFAULT_CAPACITOR_100000pF_2_1!!CAP!!CAP_0402LF-0.1UF,16V,10%,X7R,A36096-030!!
S!C9G22!!DEFAULT_CAPACITOR_10.000000pF_2_1!!CAP!!CAP_0402LF-10.0PF,50V,5%,COG,A36094-025!!
S!C4B4!27!DEFAULT_CAPACITOR_2200pF_2_1!!CAP!!CAP_0402LF-100.0PF,50V,5%,COG,A36095-026!!
S!C4G6!27!DEFAULT_CAPACITOR_2200pF_2_1!!CAP!!CAP_0402LF-100.0PF,50V,5%,COG,A36095-026!!
S!C7B10!27!DEFAULT_CAPACITOR_2200pF_2_1!!CAP!!CAP_0402LF-100.0PF,50V,5%,COG,A36095-026!!
S!C7F9!27!DEFAULT_CAPACITOR_100000pF_2_1!!CAP!!CAP_0402LF-100.0PF,50V,5%,COG,A36095-026!!
S!C1U17!!DEFAULT_CAPACITOR_100.000000pF_2_1!!CAP!!CAP_0402LF-100.0PF,50V,5%,COG,A36095-026!!
S!C1U2!!DEFAULT_CAPACITOR_100.000000pF_2_1!!CAP!!CAP_0402LF-100.0PF,50V,5%,COG,A36095-026!!
S!C1T20!!DEFAULT_CAPACITOR_100.000000pF_2_1!!CAP!!CAP_0402LF-100.0PF,50V,5%,COG,A36095-026!!
S!C9F18!!DEFAULT_CAPACITOR_100.000000pF_2_1!!CAP!!CAP_0402LF-100.0PF,50V,5%,COG,A36095-026!!
S!C7B9!1!!!CAP!!CAP_0402LF-1000PF,50V,10%,EMPTY,A36096-046!!
S!C4G7!1!!!CAP!!CAP_0402LF-1000PF,50V,10%,EMPTY,A36096-046!!
S!C4B5!1!!!CAP!!CAP_0402LF-1000PF,50V,10%,EMPTY,A36096-046!!
S!C7F8!1!!!CAP!!CAP_0402LF-1000PF,50V,10%,EMPTY,A36096-046!!
S!C8E17!1!!!CAP!!CAP_0402LF-1000PF,50V,10%,EMPTY,A36096-046!!
S!C8A10!56!!!CAP!!CAP_0402LF-1000PF,50V,10%,EMPTY,A36096-046!!
S!C4G23!18!!!CAP!!CAP_0402LF-1000PF,50V,10%,EMPTY,A36096-046!!
S!C4A2!!!!CAP!!CAP_0402LF-1000PF,50V,10%,EMPTY,A36096-046!!
S!C4G12!!!!CAP!!CAP_0402LF-1000PF,50V,10%,EMPTY,A36096-046!!
S!C4A6!!!!CAP!!CAP_0402LF-1000PF,50V,10%,EMPTY,A36096-046!!
S!C8E13!1!!!CAP!!CAP_0402LF-1000PF,50V,10%,EMPTY,A36096-046!!
S!C9F9!!!!CAP!!CAP_0402LF-1000PF,50V,10%,EMPTY,A36096-046!!
S!C9F6!!DEFAULT_CAPACITOR_1000pF_2_1!!CAP!!CAP_0402LF-1000PF,50V,10%,EMPTY,A36096-046!!
S!C4D42!!DEFAULT_CAPACITOR_1000pF_2_1!!CAP!!CAP_0402LF-1000PF,50V,10%,X7R,A36096-046!!
S!C1C23!!DEFAULT_CAPACITOR_1000pF_2_1!!CAP!!CAP_0402LF-1000PF,50V,10%,X7R,A36096-046!!
S!C3P6!!DEFAULT_CAPACITOR_1000pF_2_1!!CAP!!CAP_0402LF-1000PF,50V,10%,X7R,A36096-046!!
S!C4D33!!DEFAULT_CAPACITOR_1000pF_2_1!!CAP!!CAP_0402LF-1000PF,50V,10%,X7R,A36096-046!!
S!C8A9!!DEFAULT_CAPACITOR_1000pF_2_1!!CAP!!CAP_0402LF-1000PF,50V,10%,X7R,A36096-046!!
S!C7F14!!DEFAULT_CAPACITOR_1000pF_2_1!!CAP!!CAP_0402LF-1000PF,50V,10%,X7R,A36096-046!!
S!C7B3!!DEFAULT_CAPACITOR_1000pF_2_1!!CAP!!CAP_0402LF-1000PF,50V,10%,X7R,A36096-046!!
S!C1G21!!DEFAULT_CAPACITOR_1000pF_2_1!!CAP!!CAP_0402LF-1000PF,50V,10%,X7R,A36096-046!!
S!C1B4!!DEFAULT_CAPACITOR_1000pF_2_1!!CAP!!CAP_0402LF-1000PF,50V,10%,X7R,A36096-046!!
S!C7B12!26!DEFAULT_CAPACITOR_1000pF_2_1!!CAP!!CAP_0402LF-1000PF,50V,10%,X7R,A36096-046!!
S!C4G9!17!DEFAULT_CAPACITOR_1000pF_2_1!!CAP!!CAP_0402LF-1000PF,50V,10%,X7R,A36096-046!!
S!C4B8!17!DEFAULT_CAPACITOR_1000pF_2_1!!CAP!!CAP_0402LF-1000PF,50V,10%,X7R,A36096-046!!
S!C7F11!17!DEFAULT_CAPACITOR_1000pF_2_1!!CAP!!CAP_0402LF-1000PF,50V,10%,X7R,A36096-046!!
S!C8F2!17!DEFAULT_CAPACITOR_1000pF_2_1!!CAP!!CAP_0402LF-1000PF,50V,10%,X7R,A36096-046!!
S!C4G14!8!DEFAULT_CAPACITOR_1000pF_2_1!!CAP!!CAP_0402LF-1000PF,50V,10%,X7R,A36096-046!!
S!C4A12!!DEFAULT_CAPACITOR_1000pF_2_1!!CAP!!CAP_0402LF-1000PF,50V,10%,X7R,A36096-046!!
S!C4G13!!DEFAULT_CAPACITOR_1000pF_2_1!!CAP!!CAP_0402LF-1000PF,50V,10%,X7R,A36096-046!!
S!C4A3!!DEFAULT_CAPACITOR_1000pF_2_1!!CAP!!CAP_0402LF-1000PF,50V,10%,X7R,A36096-046!!
S!C8A11!60!DEFAULT_CAPACITOR_1000pF_2_1!!CAP!!CAP_0402LF-1000PF,50V,10%,X7R,A36096-046!!
S!C8A3!!DEFAULT_CAPACITOR_1000pF_2_1!!CAP!!CAP_0402LF-1000PF,50V,10%,X7R,A36096-046!!
S!C3P2!416!DEFAULT_CAPACITOR_1000pF_2_1!!CAP!!CAP_0402LF-1000PF,50V,10%,X7R,A36096-046!!
S!C4D40!347!DEFAULT_CAPACITOR_1000pF_2_1!!CAP!!CAP_0402LF-1000PF,50V,10%,X7R,A36096-046!!
S!C7A35!!DEFAULT_CAPACITOR_1000pF_2_1!!CAP!!CAP_0402LF-1000PF,50V,10%,X7R,A36096-046!!
S!C1G26!28!DEFAULT_CAPACITOR_1000pF_2_1!!CAP!!CAP_0402LF-1000PF,50V,10%,X7R,A36096-046!!
S!C1B8!103!DEFAULT_CAPACITOR_1000pF_2_1!!CAP!!CAP_0402LF-1000PF,50V,10%,X7R,A36096-046!!
S!C7E10!17!DEFAULT_CAPACITOR_1000pF_2_1!!CAP!!CAP_0402LF-1000PF,50V,10%,X7R,A36096-046!!
S!C9F8!!DEFAULT_CAPACITOR_1000pF_2_1!!CAP!!CAP_0402LF-1000PF,50V,10%,X7R,A36096-046!!
S!C9F10!!DEFAULT_CAPACITOR_27.000000pF_2_1!!CAP!!CAP_0402LF-1000PF,50V,10%,X7R,A36096-046!!
S!C7G1!89!DEFAULT_CAPACITOR_1000pF_2_1!!CAP!!CAP_0402LF-1000PF,50V,10%,X7R,A36096-046!!
S!C4D20!27!DEFAULT_CAPACITOR_1000pF_2_1!!CAP!!CAP_0402LF-1000PF,50V,10%,X7R,A36096-046!!
S!C1C8!!DEFAULT_CAPACITOR_1000pF_2_1!!CAP!!CAP_0402LF-1000PF,50V,10%,X7R,A36096-046!!
S!C7C13!!DEFAULT_CAPACITOR_18.000000pF_2_1!!CAP!!CAP_0402LF-18PF,50V,5%,C0G,A36095-042!!
S!C7C15!!DEFAULT_CAPACITOR_18.000000pF_2_1!!CAP!!CAP_0402LF-18PF,50V,5%,C0G,A36095-042!!
S!C9E9!!DEFAULT_CAPACITOR_22.000000pF_2_1!!CAP!!CAP_0402LF-22.0PF,50V,5%,COG,A36095-030!!
S!C9E8!!DEFAULT_CAPACITOR_22.000000pF_2_1!!CAP!!CAP_0402LF-22.0PF,50V,5%,COG,A36095-030!!
S!C7B14!27!DEFAULT_CAPACITOR_10.000000pF_2_1!!CAP!!CAP_0402LF-2200PF,50V,10%,X7R,A36096-075!!
S!C4B7!26!DEFAULT_CAPACITOR_680.000000pF_2_1!!CAP!!CAP_0402LF-2200PF,50V,10%,X7R,A36096-075!!
S!C4B9!27!DEFAULT_CAPACITOR_10.000000pF_2_1!!CAP!!CAP_0402LF-2200PF,50V,10%,X7R,A36096-075!!
S!C4G10!27!DEFAULT_CAPACITOR_10.000000pF_2_1!!CAP!!CAP_0402LF-2200PF,50V,10%,X7R,A36096-075!!
S!C4G11!26!DEFAULT_CAPACITOR_680.000000pF_2_1!!CAP!!CAP_0402LF-2200PF,50V,10%,X7R,A36096-075!!
S!C7B13!26!DEFAULT_CAPACITOR_680.000000pF_2_1!!CAP!!CAP_0402LF-2200PF,50V,10%,X7R,A36096-075!!
S!C7F12!27!DEFAULT_CAPACITOR_100000pF_2_1!!CAP!!CAP_0402LF-2200PF,50V,10%,X7R,A36096-075!!
S!C7F13!26!DEFAULT_CAPACITOR_680.000000pF_2_1!!CAP!!CAP_0402LF-2200PF,50V,10%,X7R,A36096-075!!
S!C8F1!5!DEFAULT_CAPACITOR_2200pF_2_1!!CAP!!CAP_0402LF-2200PF,50V,10%,X7R,A36096-075!!
S!C2L2!!DEFAULT_CAPACITOR_220.000000pF_2_1!YES!CAP!!CAP_0402LF-220PF,50V,10%,X7R,A36096-050!!
S!C8A2!!DEFAULT_CAPACITOR_220.000000pF_2_1!YES!CAP!!CAP_0402LF-220PF,50V,10%,X7R,A36096-050!!
S!C3N39!421!DEFAULT_CAPACITOR_220.000000pF_2_1!!CAP!!CAP_0402LF-220PF,50V,10%,X7R,A36096-050!!
S!C4D44!378!DEFAULT_CAPACITOR_220.000000pF_2_1!!CAP!!CAP_0402LF-220PF,50V,10%,X7R,A36096-050!!
S!C7A29!!DEFAULT_CAPACITOR_220.000000pF_2_1!!CAP!!CAP_0402LF-220PF,50V,10%,X7R,A36096-050!!
S!C7A28!!DEFAULT_CAPACITOR_220.000000pF_2_1!!CAP!!CAP_0402LF-220PF,50V,10%,X7R,A36096-050!!
S!C1G24!!DEFAULT_CAPACITOR_220.000000pF_2_1!!CAP!!CAP_0402LF-220PF,50V,10%,X7R,A36096-050!!
S!C1G16!1!DEFAULT_CAPACITOR_220.000000pF_2_1!YES!CAP!!CAP_0402LF-220PF,50V,10%,X7R,A36096-050!!
S!C1B11!101!DEFAULT_CAPACITOR_220.000000pF_2_1!!CAP!!CAP_0402LF-220PF,50V,10%,X7R,A36096-050!!
S!C1B12!116!DEFAULT_CAPACITOR_220.000000pF_2_1!YES!CAP!!CAP_0402LF-220PF,50V,10%,X7R,A36096-050!!
S!C7G4!98!DEFAULT_CAPACITOR_220.000000pF_2_1!YES!CAP!!CAP_0402LF-220PF,50V,10%,X7R,A36096-050!!
S!C7G3!83!DEFAULT_CAPACITOR_220.000000pF_2_1!!CAP!!CAP_0402LF-220PF,50V,10%,X7R,A36096-050!!
S!C4D45!4!DEFAULT_CAPACITOR_220.000000pF_2_1!YES!CAP!!CAP_0402LF-220PF,50V,10%,X7R,A36096-050!!
S!C4D18!31!DEFAULT_CAPACITOR_220.000000pF_2_1!!CAP!!CAP_0402LF-220PF,50V,10%,X7R,A36096-050!!
S!C4D17!3!DEFAULT_CAPACITOR_220.000000pF_2_1!!CAP!!CAP_0402LF-220PF,50V,10%,X7R,A36096-050!!
S!C4D29!30!DEFAULT_CAPACITOR_220.000000pF_2_1!YES!CAP!!CAP_0402LF-220PF,50V,10%,X7R,A36096-050!!
S!C1D1!!DEFAULT_CAPACITOR_220.000000pF_2_1!YES!CAP!!CAP_0402LF-220PF,50V,10%,X7R,A36096-050!!
S!C1C11!!DEFAULT_CAPACITOR_220.000000pF_2_1!!CAP!!CAP_0402LF-220PF,50V,10%,X7R,A36096-050!!
S!C1C10!!DEFAULT_CAPACITOR_220.000000pF_2_1!!CAP!!CAP_0402LF-220PF,50V,10%,X7R,A36096-050!!
S!C1C16!!DEFAULT_CAPACITOR_220.000000pF_2_1!YES!CAP!!CAP_0402LF-220PF,50V,10%,X7R,A36096-050!!
S!C8F19!!DEFAULT_CAPACITOR_27.000000pF_2_1!!CAP!!CAP_0402LF-27.0PF,50V,5%,COG,A36095-038!!
S!C8F18!!DEFAULT_CAPACITOR_27.000000pF_2_1!!CAP!!CAP_0402LF-27.0PF,50V,5%,COG,A36095-038!!
S!C8E16!4!DEFAULT_CAPACITOR_270.000000pF_2_1!!CAP!!CAP_0402LF-270PF,50V,10%,X7R,A36096-065!!
S!C7A34!26!!!CAP!!CAP_0402LF-3300PF,50V,10%,EMPTY,A36096-091!!
S!C4F12!26!!!CAP!!CAP_0402LF-3300PF,50V,10%,EMPTY,A36096-091!!
S!C4A16!26!!!CAP!!CAP_0402LF-3300PF,50V,10%,EMPTY,A36096-091!!
S!C7F3!26!!!CAP!!CAP_0402LF-3300PF,50V,10%,EMPTY,A36096-091!!
S!C8F3!26!!!CAP!!CAP_0402LF-3300PF,50V,10%,EMPTY,A36096-091!!
S!C9G18!!DEFAULT_CAPACITOR_47.000000pF_2_1!!CAP!!CAP_0402LF-47.0PF,50V,5%,COG,A36095-025!!
S!C9G15!!DEFAULT_CAPACITOR_47.000000pF_2_1!!CAP!!CAP_0402LF-47.0PF,50V,5%,COG,A36095-025!!
S!C9G14!!DEFAULT_CAPACITOR_47.000000pF_2_1!!CAP!!CAP_0402LF-47.0PF,50V,5%,COG,A36095-025!!
S!C1U21!!DEFAULT_CAPACITOR_47.000000pF_2_1!!CAP!!CAP_0402LF-47.0PF,50V,5%,COG,A36095-025!!
S!C9G21!!DEFAULT_CAPACITOR_47.000000pF_2_1!!CAP!!CAP_0402LF-47.0PF,50V,5%,COG,A36095-025!!
S!C9G17!!DEFAULT_CAPACITOR_47.000000pF_2_1!!CAP!!CAP_0402LF-47.0PF,50V,5%,COG,A36095-025!!
S!C9G20!!DEFAULT_CAPACITOR_47.000000pF_2_1!!CAP!!CAP_0402LF-47.0PF,50V,5%,COG,A36095-025!!
S!C9F22!!DEFAULT_CAPACITOR_470.000000pF_2_1!!CAP!!CAP_0402LF-470PF,50V,10%,X7R,A36096-049!!
S!C9G1!!DEFAULT_CAPACITOR_470.000000pF_2_1!!CAP!!CAP_0402LF-470PF,50V,10%,X7R,A36096-049!!
S!C9G3!!DEFAULT_CAPACITOR_470.000000pF_2_1!!CAP!!CAP_0402LF-470PF,50V,10%,X7R,A36096-049!!
S!C9G2!!DEFAULT_CAPACITOR_470.000000pF_2_1!!CAP!!CAP_0402LF-470PF,50V,10%,X7R,A36096-049!!
S!C1T42!!DEFAULT_CAPACITOR_470000pF_2_1!!CAP!!CAP_0603-0.47UF,16V,10%,X7R,202297-006!!
S!C8A6!42!DEFAULT_CAPACITOR_1e+06pF_2_1!!CAP!!CAP_0603-10UF,6.3V,20%,X6S,E15431-002!!
S!C2N14!!DEFAULT_CAPACITOR_1e+07pF_2_1!!CAP!!CAP_0603-10UF,6.3V,20%,X6S,E15431-002!!
S!C8C6!!DEFAULT_CAPACITOR_1e+07pF_2_1!!CAP!!CAP_0603-10UF,6.3V,20%,X6S,E15431-002!!
S!C2N23!!DEFAULT_CAPACITOR_1e+07pF_2_1!!CAP!!CAP_0603-10UF,6.3V,20%,X6S,E15431-002!!
S!C8C5!!DEFAULT_CAPACITOR_1e+07pF_2_1!!CAP!!CAP_0603-10UF,6.3V,20%,X6S,E15431-002!!
S!C8C4!!DEFAULT_CAPACITOR_1e+07pF_2_1!!CAP!!CAP_0603-10UF,6.3V,20%,X6S,E15431-002!!
S!C8C3!!DEFAULT_CAPACITOR_1e+07pF_2_1!!CAP!!CAP_0603-10UF,6.3V,20%,X6S,E15431-002!!
S!C7D2!!DEFAULT_CAPACITOR_1e+07pF_2_1!!CAP!!CAP_0603-10UF,6.3V,20%,X6S,E15431-002!!
S!C2N21!!DEFAULT_CAPACITOR_1e+07pF_2_1!!CAP!!CAP_0603-10UF,6.3V,20%,X6S,E15431-002!!
S!C2N22!!DEFAULT_CAPACITOR_1e+07pF_2_1!!CAP!!CAP_0603-10UF,6.3V,20%,X6S,E15431-002!!
S!C2N24!!DEFAULT_CAPACITOR_1e+07pF_2_1!!CAP!!CAP_0603-10UF,6.3V,20%,X6S,E15431-002!!
S!C2N17!!DEFAULT_CAPACITOR_1e+07pF_2_1!!CAP!!CAP_0603-10UF,6.3V,20%,X6S,E15431-002!!
S!C9F3!!DEFAULT_CAPACITOR_1e+07pF_2_1!!CAP!!CAP_0603-10UF,6.3V,20%,X6S,E15431-002!!
S!C9E10!!DEFAULT_CAPACITOR_1e+07pF_2_1!!CAP!!CAP_0603-10UF,6.3V,20%,X6S,E15431-002!!
S!C1T7!!DEFAULT_CAPACITOR_1e+07pF_2_1!!CAP!!CAP_0603-10UF,6.3V,20%,X6S,E15431-002!!
S!C1T15!!DEFAULT_CAPACITOR_1e+07pF_2_1!!CAP!!CAP_0603-10UF,6.3V,20%,X6S,E15431-002!!
S!C1R22!!DEFAULT_CAPACITOR_1e+07pF_2_1!!CAP!!CAP_0603-10UF,6.3V,20%,X6S,E15431-002!!
S!C1R30!!DEFAULT_CAPACITOR_1e+07pF_2_1!!CAP!!CAP_0603-10UF,6.3V,20%,X6S,E15431-002!!
S!C1T4!!DEFAULT_CAPACITOR_1e+07pF_2_1!!CAP!!CAP_0603-10UF,6.3V,20%,X6S,E15431-002!!
S!C1R13!!DEFAULT_CAPACITOR_1e+07pF_2_1!!CAP!!CAP_0603-10UF,6.3V,20%,X6S,E15431-002!!
S!C1R17!!DEFAULT_CAPACITOR_1e+07pF_2_1!!CAP!!CAP_0603-10UF,6.3V,20%,X6S,E15431-002!!
S!C1R16!!DEFAULT_CAPACITOR_1e+07pF_2_1!!CAP!!CAP_0603-10UF,6.3V,20%,X6S,E15431-002!!
S!C2R11!20!DEFAULT_CAPACITOR_4.7e+06pF_2_1!!CAP!!CAP_0603-4.7UF,6.3V,10%,X6S,E15431-003!!
S!C3T11!26!DEFAULT_CAPACITOR_10000pF_2_1!!CAP!!CAP_0603-4.7UF,6.3V,10%,X6S,E15431-003!!
S!C3M10!26!DEFAULT_CAPACITOR_4.7e+06pF_2_1!!CAP!!CAP_0603-4.7UF,6.3V,10%,X6S,E15431-003!!
S!C6U6!26!DEFAULT_CAPACITOR_4.7e+06pF_2_1!!CAP!!CAP_0603-4.7UF,6.3V,10%,X6S,E15431-003!!
S!C6L12!26!DEFAULT_CAPACITOR_4.7e+06pF_2_1!!CAP!!CAP_0603-4.7UF,6.3V,10%,X6S,E15431-003!!
S!C6U12!!DEFAULT_CAPACITOR_4.7e+06pF_2_1!!CAP!!CAP_0603-4.7UF,6.3V,10%,X6S,E15431-003!!
S!C4A11!!DEFAULT_CAPACITOR_4.7e+06pF_2_1!!CAP!!CAP_0603-4.7UF,6.3V,10%,X6S,E15431-003!!
S!C6U11!!DEFAULT_CAPACITOR_4.7e+06pF_2_1!!CAP!!CAP_0603-4.7UF,6.3V,10%,X6S,E15431-003!!
S!C4A7!!DEFAULT_CAPACITOR_4.7e+06pF_2_1!!CAP!!CAP_0603-4.7UF,6.3V,10%,X6S,E15431-003!!
S!C1T44!!DEFAULT_CAPACITOR_4.7e+06pF_2_1!!CAP!!CAP_0603-4.7UF,6.3V,10%,X6S,E15431-003!!
S!C9P14!6!DEFAULT_CAPACITOR_33000pF_2_1!!CAP!!CAP_0603LF-0.033UF,50V,10%,X7R,603269-064!!
S!C7B30!27!DEFAULT_CAPACITOR_100000pF_2_1!!CAP!!CAP_0603LF-0.1UF,25V,10%,X7R,602433-020!!
S!C4G26!27!DEFAULT_CAPACITOR_100000pF_2_1!!CAP!!CAP_0603LF-0.1UF,25V,10%,X7R,602433-020!!
S!C4B15!27!DEFAULT_CAPACITOR_100000pF_2_1!!CAP!!CAP_0603LF-0.1UF,25V,10%,X7R,602433-020!!
S!C7F4!27!DEFAULT_CAPACITOR_100000pF_2_1!!CAP!!CAP_0603LF-0.1UF,25V,10%,X7R,602433-020!!
S!C8E12!27!DEFAULT_CAPACITOR_100000pF_2_1!!CAP!!CAP_0603LF-0.1UF,25V,10%,X7R,602433-020!!
S!C8A4!41!DEFAULT_CAPACITOR_100000pF_2_1!!CAP!!CAP_0603LF-0.1UF,25V,10%,X7R,602433-020!!
S!C8E6!27!DEFAULT_CAPACITOR_100000pF_2_1!!CAP!!CAP_0603LF-0.1UF,25V,10%,X7R,602433-020!!
S!C6F5!!DEFAULT_CAPACITOR_1e+07pF_2_1!!CAP!!CAP_0603LF-10UF,4V,20%,X6S,E15431-001!!
S!C4L1!!DEFAULT_CAPACITOR_1e+07pF_2_1!!CAP!!CAP_0603LF-10UF,4V,20%,X6S,E15431-001!!
S!C7U3!!DEFAULT_CAPACITOR_1e+07pF_2_1!!CAP!!CAP_0603LF-10UF,4V,20%,X6S,E15431-001!!
S!C6F6!!DEFAULT_CAPACITOR_1e+07pF_2_1!!CAP!!CAP_0603LF-10UF,4V,20%,X6S,E15431-001!!
S!C4T6!!DEFAULT_CAPACITOR_1e+07pF_2_1!!CAP!!CAP_0603LF-10UF,4V,20%,X6S,E15431-001!!
S!C4T5!!DEFAULT_CAPACITOR_1e+07pF_2_1!!CAP!!CAP_0603LF-10UF,4V,20%,X6S,E15431-001!!
S!C6G1!!DEFAULT_CAPACITOR_1e+07pF_2_1!!CAP!!CAP_0603LF-10UF,4V,20%,X6S,E15431-001!!
S!C6G2!!DEFAULT_CAPACITOR_1e+07pF_2_1!!CAP!!CAP_0603LF-10UF,4V,20%,X6S,E15431-001!!
S!C4U2!!DEFAULT_CAPACITOR_1e+07pF_2_1!!CAP!!CAP_0603LF-10UF,4V,20%,X6S,E15431-001!!
S!C4U1!!DEFAULT_CAPACITOR_1e+07pF_2_1!!CAP!!CAP_0603LF-10UF,4V,20%,X6S,E15431-001!!
S!C6G4!!DEFAULT_CAPACITOR_1e+07pF_2_1!!CAP!!CAP_0603LF-10UF,4V,20%,X6S,E15431-001!!
S!C6G5!!DEFAULT_CAPACITOR_1e+07pF_2_1!!CAP!!CAP_0603LF-10UF,4V,20%,X6S,E15431-001!!
S!C4U4!!DEFAULT_CAPACITOR_1e+07pF_2_1!!CAP!!CAP_0603LF-10UF,4V,20%,X6S,E15431-001!!
S!C4U3!!DEFAULT_CAPACITOR_1e+07pF_2_1!!CAP!!CAP_0603LF-10UF,4V,20%,X6S,E15431-001!!
S!C4L2!!DEFAULT_CAPACITOR_1e+07pF_2_1!!CAP!!CAP_0603LF-10UF,4V,20%,X6S,E15431-001!!
S!C6A3!!DEFAULT_CAPACITOR_1e+07pF_2_1!!CAP!!CAP_0603LF-10UF,4V,20%,X6S,E15431-001!!
S!C6A2!!DEFAULT_CAPACITOR_1e+07pF_2_1!!CAP!!CAP_0603LF-10UF,4V,20%,X6S,E15431-001!!
S!C4L3!!DEFAULT_CAPACITOR_1e+07pF_2_1!!CAP!!CAP_0603LF-10UF,4V,20%,X6S,E15431-001!!
S!C4L4!!DEFAULT_CAPACITOR_1e+07pF_2_1!!CAP!!CAP_0603LF-10UF,4V,20%,X6S,E15431-001!!
S!C6A7!!DEFAULT_CAPACITOR_1e+07pF_2_1!!CAP!!CAP_0603LF-10UF,4V,20%,X6S,E15431-001!!
S!C6A6!!DEFAULT_CAPACITOR_1e+07pF_2_1!!CAP!!CAP_0603LF-10UF,4V,20%,X6S,E15431-001!!
S!C4M3!!DEFAULT_CAPACITOR_1e+07pF_2_1!!CAP!!CAP_0603LF-10UF,4V,20%,X6S,E15431-001!!
S!C4M4!!DEFAULT_CAPACITOR_1e+07pF_2_1!!CAP!!CAP_0603LF-10UF,4V,20%,X6S,E15431-001!!
S!C6B2!!DEFAULT_CAPACITOR_1e+07pF_2_1!!CAP!!CAP_0603LF-10UF,4V,20%,X6S,E15431-001!!
S!C6B1!!DEFAULT_CAPACITOR_1e+07pF_2_1!!CAP!!CAP_0603LF-10UF,4V,20%,X6S,E15431-001!!
S!C7U4!!DEFAULT_CAPACITOR_1e+07pF_2_1!!CAP!!CAP_0603LF-10UF,4V,20%,X6S,E15431-001!!
S!C7U5!!DEFAULT_CAPACITOR_1e+07pF_2_1!!CAP!!CAP_0603LF-10UF,4V,20%,X6S,E15431-001!!
S!C7T2!!DEFAULT_CAPACITOR_1e+07pF_2_1!!CAP!!CAP_0603LF-10UF,4V,20%,X6S,E15431-001!!
S!C7T3!!DEFAULT_CAPACITOR_1e+07pF_2_1!!CAP!!CAP_0603LF-10UF,4V,20%,X6S,E15431-001!!
S!C7U6!!DEFAULT_CAPACITOR_1e+07pF_2_1!!CAP!!CAP_0603LF-10UF,4V,20%,X6S,E15431-001!!
S!C3F3!!DEFAULT_CAPACITOR_1e+07pF_2_1!!CAP!!CAP_0603LF-10UF,4V,20%,X6S,E15431-001!!
S!C3F4!!DEFAULT_CAPACITOR_1e+07pF_2_1!!CAP!!CAP_0603LF-10UF,4V,20%,X6S,E15431-001!!
S!C3G3!!DEFAULT_CAPACITOR_1e+07pF_2_1!!CAP!!CAP_0603LF-10UF,4V,20%,X6S,E15431-001!!
S!C3G7!!DEFAULT_CAPACITOR_1e+07pF_2_1!!CAP!!CAP_0603LF-10UF,4V,20%,X6S,E15431-001!!
S!C3G4!!DEFAULT_CAPACITOR_1e+07pF_2_1!!CAP!!CAP_0603LF-10UF,4V,20%,X6S,E15431-001!!
S!C3G8!!DEFAULT_CAPACITOR_1e+07pF_2_1!!CAP!!CAP_0603LF-10UF,4V,20%,X6S,E15431-001!!
S!C3A3!2!DEFAULT_CAPACITOR_1e+07pF_2_1!!CAP!!CAP_0603LF-10UF,4V,20%,X6S,E15431-001!!
S!C3A7!1!DEFAULT_CAPACITOR_1e+07pF_2_1!!CAP!!CAP_0603LF-10UF,4V,20%,X6S,E15431-001!!
S!C3B1!6!DEFAULT_CAPACITOR_1e+07pF_2_1!!CAP!!CAP_0603LF-10UF,4V,20%,X6S,E15431-001!!
S!C3A4!5!DEFAULT_CAPACITOR_1e+07pF_2_1!!CAP!!CAP_0603LF-10UF,4V,20%,X6S,E15431-001!!
S!C7M3!4!DEFAULT_CAPACITOR_1e+07pF_2_1!!CAP!!CAP_0603LF-10UF,4V,20%,X6S,E15431-001!!
S!C7M4!9!DEFAULT_CAPACITOR_1e+07pF_2_1!!CAP!!CAP_0603LF-10UF,4V,20%,X6S,E15431-001!!
S!C7L6!10!DEFAULT_CAPACITOR_1e+07pF_2_1!!CAP!!CAP_0603LF-10UF,4V,20%,X6S,E15431-001!!
S!C7L7!8!DEFAULT_CAPACITOR_1e+07pF_2_1!!CAP!!CAP_0603LF-10UF,4V,20%,X6S,E15431-001!!
S!C7L2!11!DEFAULT_CAPACITOR_1e+07pF_2_1!!CAP!!CAP_0603LF-10UF,4V,20%,X6S,E15431-001!!
S!C7L3!15!DEFAULT_CAPACITOR_1e+07pF_2_1!!CAP!!CAP_0603LF-10UF,4V,20%,X6S,E15431-001!!
S!C3A8!13!DEFAULT_CAPACITOR_1e+07pF_2_1!!CAP!!CAP_0603LF-10UF,4V,20%,X6S,E15431-001!!
S!C3B2!14!DEFAULT_CAPACITOR_1e+07pF_2_1!!CAP!!CAP_0603LF-10UF,4V,20%,X6S,E15431-001!!
S!C3M24!!DEFAULT_CAPACITOR_1e+07pF_2_1!!CAP!!CAP_0603LF-10UF,4V,20%,X6S,E15431-001!!
S!C2N6!!DEFAULT_CAPACITOR_1e+07pF_2_1!!CAP!!CAP_0603LF-10UF,4V,20%,X6S,E15431-001!!
S!C2M5!!DEFAULT_CAPACITOR_1e+07pF_2_1!!CAP!!CAP_0603LF-10UF,4V,20%,X6S,E15431-001!!
S!C2M10!6!DEFAULT_CAPACITOR_1e+07pF_2_1!!CAP!!CAP_0603LF-10UF,4V,20%,X6S,E15431-001!!
S!C3M17!1!DEFAULT_CAPACITOR_1e+07pF_2_1!!CAP!!CAP_0603LF-10UF,4V,20%,X6S,E15431-001!!
S!C3M18!1!DEFAULT_CAPACITOR_1e+07pF_2_1!!CAP!!CAP_0603LF-10UF,4V,20%,X6S,E15431-001!!
S!C3M23!!DEFAULT_CAPACITOR_1e+07pF_2_1!!CAP!!CAP_0603LF-10UF,4V,20%,X6S,E15431-001!!
S!C6U15!!DEFAULT_CAPACITOR_1e+07pF_2_1!!CAP!!CAP_0603LF-10UF,4V,20%,X6S,E15431-001!!
S!C6U16!17!DEFAULT_CAPACITOR_1e+07pF_2_1!!CAP!!CAP_0603LF-10UF,4V,20%,X6S,E15431-001!!
S!C6L4!!DEFAULT_CAPACITOR_1e+07pF_2_1!!CAP!!CAP_0603LF-10UF,4V,20%,X6S,E15431-001!!
S!C6U13!!DEFAULT_CAPACITOR_1e+07pF_2_1!!CAP!!CAP_0603LF-10UF,4V,20%,X6S,E15431-001!!
S!C6L5!!DEFAULT_CAPACITOR_1e+07pF_2_1!!CAP!!CAP_0603LF-10UF,4V,20%,X6S,E15431-001!!
S!C6L3!!DEFAULT_CAPACITOR_1e+07pF_2_1!!CAP!!CAP_0603LF-10UF,4V,20%,X6S,E15431-001!!
S!C6U14!!DEFAULT_CAPACITOR_1e+07pF_2_1!!CAP!!CAP_0603LF-10UF,4V,20%,X6S,E15431-001!!
S!C4A15!!DEFAULT_CAPACITOR_1e+07pF_2_1!!CAP!!CAP_0603LF-10UF,4V,20%,X6S,E15431-001!!
S!C5D54!!DEFAULT_CAPACITOR_1e+07pF_2_1!!CAP!!CAP_0603LF-10UF,4V,20%,X6S,E15431-001!!
S!C5D55!!DEFAULT_CAPACITOR_1e+07pF_2_1!!CAP!!CAP_0603LF-10UF,4V,20%,X6S,E15431-001!!
S!C5D56!!DEFAULT_CAPACITOR_1e+07pF_2_1!!CAP!!CAP_0603LF-10UF,4V,20%,X6S,E15431-001!!
S!C5D57!!DEFAULT_CAPACITOR_1e+07pF_2_1!!CAP!!CAP_0603LF-10UF,4V,20%,X6S,E15431-001!!
S!C5D9!!DEFAULT_CAPACITOR_1e+07pF_2_1!!CAP!!CAP_0603LF-10UF,4V,20%,X6S,E15431-001!!
S!C5D6!!DEFAULT_CAPACITOR_1e+07pF_2_1!!CAP!!CAP_0603LF-10UF,4V,20%,X6S,E15431-001!!
S!C5D7!!DEFAULT_CAPACITOR_1e+07pF_2_1!!CAP!!CAP_0603LF-10UF,4V,20%,X6S,E15431-001!!
S!C5D8!!DEFAULT_CAPACITOR_1e+07pF_2_1!!CAP!!CAP_0603LF-10UF,4V,20%,X6S,E15431-001!!
S!C2D43!!DEFAULT_CAPACITOR_1e+07pF_2_1!!CAP!!CAP_0603LF-10UF,4V,20%,X6S,E15431-001!!
S!C2D41!!DEFAULT_CAPACITOR_1e+07pF_2_1!!CAP!!CAP_0603LF-10UF,4V,20%,X6S,E15431-001!!
S!C2D44!!DEFAULT_CAPACITOR_1e+07pF_2_1!!CAP!!CAP_0603LF-10UF,4V,20%,X6S,E15431-001!!
S!C2D42!!DEFAULT_CAPACITOR_1e+07pF_2_1!!CAP!!CAP_0603LF-10UF,4V,20%,X6S,E15431-001!!
S!C2D7!!DEFAULT_CAPACITOR_1e+07pF_2_1!!CAP!!CAP_0603LF-10UF,4V,20%,X6S,E15431-001!!
S!C2D4!!DEFAULT_CAPACITOR_1e+07pF_2_1!!CAP!!CAP_0603LF-10UF,4V,20%,X6S,E15431-001!!
S!C2D5!!DEFAULT_CAPACITOR_1e+07pF_2_1!!CAP!!CAP_0603LF-10UF,4V,20%,X6S,E15431-001!!
S!C2D6!!DEFAULT_CAPACITOR_1e+07pF_2_1!!CAP!!CAP_0603LF-10UF,4V,20%,X6S,E15431-001!!
S!C5D10!185!DEFAULT_CAPACITOR_1e+07pF_2_1!!CAP!!CAP_0603LF-10UF,4V,20%,X6S,E15431-001!!
S!C5D12!186!DEFAULT_CAPACITOR_1e+07pF_2_1!!CAP!!CAP_0603LF-10UF,4V,20%,X6S,E15431-001!!
S!C5D11!187!DEFAULT_CAPACITOR_1e+07pF_2_1!!CAP!!CAP_0603LF-10UF,4V,20%,X6S,E15431-001!!
S!C5D13!118!DEFAULT_CAPACITOR_1e+07pF_2_1!!CAP!!CAP_0603LF-10UF,4V,20%,X6S,E15431-001!!
S!C2D9!!DEFAULT_CAPACITOR_1e+07pF_2_1!!CAP!!CAP_0603LF-10UF,4V,20%,X6S,E15431-001!!
S!C2D11!!DEFAULT_CAPACITOR_1e+07pF_2_1!!CAP!!CAP_0603LF-10UF,4V,20%,X6S,E15431-001!!
S!C2D10!!DEFAULT_CAPACITOR_1e+07pF_2_1!!CAP!!CAP_0603LF-10UF,4V,20%,X6S,E15431-001!!
S!C2D8!!DEFAULT_CAPACITOR_1e+07pF_2_1!!CAP!!CAP_0603LF-10UF,4V,20%,X6S,E15431-001!!
S!C3D3!!DEFAULT_CAPACITOR_1e+07pF_2_1!!CAP!!CAP_0603LF-10UF,4V,20%,X6S,E15431-001!!
S!C6D1!135!DEFAULT_CAPACITOR_1e+07pF_2_1!!CAP!!CAP_0603LF-10UF,4V,20%,X6S,E15431-001!!
S!C9B1!!DEFAULT_CAPACITOR_1e+07pF_2_1!!CAP!!CAP_0805-10UF,16V,10%,X6S,C95333-007!!
S!C9B2!!DEFAULT_CAPACITOR_1e+07pF_2_1!!CAP!!CAP_0805-10UF,16V,10%,X6S,C95333-007!!
S!C2T22!!DEFAULT_CAPACITOR_1e+07pF_2_1!!CAP!!CAP_0805-10UF,16V,10%,X6S,C95333-007!!
S!C7F5!17!DEFAULT_CAPACITOR_1e+07pF_2_1!!CAP!!CAP_0805-10UF,16V,10%,X6S,C95333-007!!
S!C3T8!!DEFAULT_CAPACITOR_1e+07pF_2_1!!CAP!!CAP_0805-10UF,16V,10%,X6S,C95333-007!!
S!C3T14!!DEFAULT_CAPACITOR_1e+07pF_2_1!!CAP!!CAP_0805-10UF,16V,10%,X6S,C95333-007!!
S!C3T12!!DEFAULT_CAPACITOR_1e+07pF_2_1!!CAP!!CAP_0805-10UF,16V,10%,X6S,C95333-007!!
S!C3M8!!DEFAULT_CAPACITOR_1e+07pF_2_1!!CAP!!CAP_0805-10UF,16V,10%,X6S,C95333-007!!
S!C3M15!!DEFAULT_CAPACITOR_1e+07pF_2_1!!CAP!!CAP_0805-10UF,16V,10%,X6S,C95333-007!!
S!C3M16!!DEFAULT_CAPACITOR_1e+07pF_2_1!!CAP!!CAP_0805-10UF,16V,10%,X6S,C95333-007!!
S!C7B5!!DEFAULT_CAPACITOR_1e+07pF_2_1!!CAP!!CAP_0805-10UF,16V,10%,X6S,C95333-007!!
S!C6U4!!DEFAULT_CAPACITOR_1e+07pF_2_1!!CAP!!CAP_0805-10UF,16V,10%,X6S,C95333-007!!
S!C4G2!!DEFAULT_CAPACITOR_1e+07pF_2_1!!CAP!!CAP_0805-10UF,16V,10%,X6S,C95333-007!!
S!C6U7!!DEFAULT_CAPACITOR_1e+07pF_2_1!!CAP!!CAP_0805-10UF,16V,10%,X6S,C95333-007!!
S!C6U8!!DEFAULT_CAPACITOR_1e+07pF_2_1!!CAP!!CAP_0805-10UF,16V,10%,X6S,C95333-007!!
S!C6L10!!DEFAULT_CAPACITOR_1e+07pF_2_1!!CAP!!CAP_0805-10UF,16V,10%,X6S,C95333-007!!
S!C6M3!!DEFAULT_CAPACITOR_1e+07pF_2_1!!CAP!!CAP_0805-10UF,16V,10%,X6S,C95333-007!!
S!C6M5!!DEFAULT_CAPACITOR_1e+07pF_2_1!!CAP!!CAP_0805-10UF,16V,10%,X6S,C95333-007!!
S!C4A19!!DEFAULT_CAPACITOR_1e+07pF_2_1!!CAP!!CAP_0805-10UF,16V,10%,X6S,C95333-007!!
S!C1B18!2!DEFAULT_CAPACITOR_1e+07pF_2_1!!CAP!!CAP_0805-10UF,16V,10%,X6S,C95333-007!!
S!C9M10!1!DEFAULT_CAPACITOR_1e+07pF_2_1!!CAP!!CAP_0805-10UF,16V,10%,X6S,C95333-007!!
S!C3L7!21!DEFAULT_CAPACITOR_1e+07pF_2_1!!CAP!!CAP_0805-10UF,16V,10%,X6S,C95333-007!!
S!C3L11!!DEFAULT_CAPACITOR_1e+07pF_2_1!!CAP!!CAP_0805-10UF,16V,10%,X6S,C95333-007!!
S!C3L9!22!DEFAULT_CAPACITOR_1e+07pF_2_1!!CAP!!CAP_0805-10UF,16V,10%,X6S,C95333-007!!
S!C3L8!!DEFAULT_CAPACITOR_1e+07pF_2_1!!CAP!!CAP_0805-10UF,16V,10%,X6S,C95333-007!!
S!C3L10!20!DEFAULT_CAPACITOR_1e+07pF_2_1!!CAP!!CAP_0805-10UF,16V,10%,X6S,C95333-007!!
S!C3L12!!DEFAULT_CAPACITOR_1e+07pF_2_1!!CAP!!CAP_0805-10UF,16V,10%,X6S,C95333-007!!
S!C3N34!426!DEFAULT_CAPACITOR_1e+07pF_2_1!!CAP!!CAP_0805-10UF,16V,10%,X6S,C95333-007!!
S!C3N36!425!DEFAULT_CAPACITOR_1e+07pF_2_1!!CAP!!CAP_0805-10UF,16V,10%,X6S,C95333-007!!
S!C6R8!336!DEFAULT_CAPACITOR_1e+07pF_2_1!!CAP!!CAP_0805-10UF,16V,10%,X6S,C95333-007!!
S!C6R10!374!DEFAULT_CAPACITOR_1e+07pF_2_1!!CAP!!CAP_0805-10UF,16V,10%,X6S,C95333-007!!
S!C6R14!371!DEFAULT_CAPACITOR_1e+07pF_2_1!!CAP!!CAP_0805-10UF,16V,10%,X6S,C95333-007!!
S!C6P24!!DEFAULT_CAPACITOR_1e+07pF_2_1!!CAP!!CAP_0805-10UF,16V,10%,X6S,C95333-007!!
S!C6R6!!DEFAULT_CAPACITOR_1e+07pF_2_1!!CAP!!CAP_0805-10UF,16V,10%,X6S,C95333-007!!
S!C6P19!!DEFAULT_CAPACITOR_1e+07pF_2_1!!CAP!!CAP_0805-10UF,16V,10%,X6S,C95333-007!!
S!C6P7!!DEFAULT_CAPACITOR_1e+07pF_2_1!!CAP!!CAP_0805-10UF,16V,10%,X6S,C95333-007!!
S!C6P15!!DEFAULT_CAPACITOR_1e+07pF_2_1!!CAP!!CAP_0805-10UF,16V,10%,X6S,C95333-007!!
S!C6P20!!DEFAULT_CAPACITOR_1e+07pF_2_1!!CAP!!CAP_0805-10UF,16V,10%,X6S,C95333-007!!
S!C1E21!!DEFAULT_CAPACITOR_1e+07pF_2_1!!CAP!!CAP_0805-10UF,16V,10%,X6S,C95333-007!!
S!C9M4!1!DEFAULT_CAPACITOR_1e+07pF_2_1!!CAP!!CAP_0805-10UF,16V,10%,X6S,C95333-007!!
S!C7E6!4!DEFAULT_CAPACITOR_1e+07pF_2_1!!CAP!!CAP_0805-10UF,16V,10%,X6S,C95333-007!!
S!C7E8!6!DEFAULT_CAPACITOR_1e+07pF_2_1!!CAP!!CAP_0805-10UF,16V,10%,X6S,C95333-007!!
S!C2U1!!DEFAULT_CAPACITOR_1e+07pF_2_1!!CAP!!CAP_0805-10UF,16V,10%,X6S,C95333-007!!
S!C2U2!!DEFAULT_CAPACITOR_1e+07pF_2_1!!CAP!!CAP_0805-10UF,16V,10%,X6S,C95333-007!!
S!C8B12!!DEFAULT_CAPACITOR_1e+07pF_2_1!!CAP!!CAP_0805-10UF,16V,10%,X6S,C95333-007!!
S!C8B6!!DEFAULT_CAPACITOR_1e+07pF_2_1!!CAP!!CAP_0805-10UF,16V,10%,X6S,C95333-007!!
S!C9R5!!DEFAULT_CAPACITOR_1e+07pF_2_1!!CAP!!CAP_0805-10UF,16V,10%,X6S,C95333-007!!
S!C1E12!!DEFAULT_CAPACITOR_1e+07pF_2_1!!CAP!!CAP_0805-10UF,16V,10%,X6S,C95333-007!!
S!C3N33!344!DEFAULT_CAPACITOR_1e+07pF_2_1!!CAP!!CAP_0805-10UF,16V,10%,X6S,C95333-007!!
S!C9N27!!DEFAULT_CAPACITOR_1e+07pF_2_1!!CAP!!CAP_0805-10UF,16V,10%,X6S,C95333-007!!
S!C9N26!!DEFAULT_CAPACITOR_1e+07pF_2_1!!CAP!!CAP_0805-10UF,16V,10%,X6S,C95333-007!!
S!C9N25!!DEFAULT_CAPACITOR_1e+07pF_2_1!!CAP!!CAP_0805-10UF,16V,10%,X6S,C95333-007!!
S!C1M27!!DEFAULT_CAPACITOR_100000pF_2_1!!CAP!!CAP_0805-10UF,16V,10%,X6S,C95333-007!!
S!C1M26!!DEFAULT_CAPACITOR_100000pF_2_1!!CAP!!CAP_0805-10UF,16V,10%,X6S,C95333-007!!
S!C1U12!!DEFAULT_CAPACITOR_1e+07pF_2_1!!CAP!!CAP_0805-10UF,16V,10%,X6S,C95333-007!!
S!C1U1!!DEFAULT_CAPACITOR_1e+07pF_2_1!!CAP!!CAP_0805-10UF,16V,10%,X6S,C95333-007!!
S!C6P13!45!DEFAULT_CAPACITOR_1e+07pF_2_1!!CAP!!CAP_0805-10UF,16V,10%,X6S,C95333-007!!
S!C6P17!17!DEFAULT_CAPACITOR_1e+07pF_2_1!!CAP!!CAP_0805-10UF,16V,10%,X6S,C95333-007!!
S!C6N8!59!DEFAULT_CAPACITOR_1e+07pF_2_1!!CAP!!CAP_0805-10UF,16V,10%,X6S,C95333-007!!
S!C6R13!60!DEFAULT_CAPACITOR_1e+07pF_2_1!!CAP!!CAP_0805-10UF,16V,10%,X6S,C95333-007!!
S!C6P22!46!DEFAULT_CAPACITOR_1e+07pF_2_1!!CAP!!CAP_0805-10UF,16V,10%,X6S,C95333-007!!
S!C6R4!4!DEFAULT_CAPACITOR_1e+07pF_2_1!!CAP!!CAP_0805-10UF,16V,10%,X6S,C95333-007!!
S!C6R11!18!DEFAULT_CAPACITOR_1e+07pF_2_1!!CAP!!CAP_0805-10UF,16V,10%,X6S,C95333-007!!
S!C3U2!35!DEFAULT_CAPACITOR_1e+07pF_2_1!!CAP!!CAP_0805-10UF,16V,10%,X6S,C95333-007!!
S!C3U6!33!DEFAULT_CAPACITOR_1e+07pF_2_1!!CAP!!CAP_0805-10UF,16V,10%,X6S,C95333-007!!
S!C3U3!56!DEFAULT_CAPACITOR_1e+07pF_2_1!!CAP!!CAP_0805-10UF,16V,10%,X6S,C95333-007!!
S!C3U7!22!DEFAULT_CAPACITOR_1e+07pF_2_1!!CAP!!CAP_0805-10UF,16V,10%,X6S,C95333-007!!
S!C3U4!34!DEFAULT_CAPACITOR_1e+07pF_2_1!!CAP!!CAP_0805-10UF,16V,10%,X6S,C95333-007!!
S!C3U9!55!DEFAULT_CAPACITOR_1e+07pF_2_1!!CAP!!CAP_0805-10UF,16V,10%,X6S,C95333-007!!
S!C6N6!73!DEFAULT_CAPACITOR_1e+07pF_2_1!!CAP!!CAP_0805-10UF,16V,10%,X6S,C95333-007!!
S!C6N3!74!DEFAULT_CAPACITOR_1e+07pF_2_1!!CAP!!CAP_0805-10UF,16V,10%,X6S,C95333-007!!
S!C6N2!75!DEFAULT_CAPACITOR_1e+07pF_2_1!!CAP!!CAP_0805-10UF,16V,10%,X6S,C95333-007!!
S!C3L2!29!DEFAULT_CAPACITOR_1e+07pF_2_1!!CAP!!CAP_0805-10UF,16V,10%,X6S,C95333-007!!
S!C3L15!9!DEFAULT_CAPACITOR_1e+07pF_2_1!!CAP!!CAP_0805-10UF,16V,10%,X6S,C95333-007!!
S!C3L4!27!DEFAULT_CAPACITOR_1e+07pF_2_1!!CAP!!CAP_0805-10UF,16V,10%,X6S,C95333-007!!
S!C3L16!16!DEFAULT_CAPACITOR_1e+07pF_2_1!!CAP!!CAP_0805-10UF,16V,10%,X6S,C95333-007!!
S!C3L13!30!DEFAULT_CAPACITOR_1e+07pF_2_1!!CAP!!CAP_0805-10UF,16V,10%,X6S,C95333-007!!
S!C3L17!17!DEFAULT_CAPACITOR_1e+07pF_2_1!!CAP!!CAP_0805-10UF,16V,10%,X6S,C95333-007!!
S!C9L11!72!DEFAULT_CAPACITOR_1e+07pF_2_1!!CAP!!CAP_0805-10UF,16V,10%,X6S,C95333-007!!
S!C9L14!71!DEFAULT_CAPACITOR_1e+07pF_2_1!!CAP!!CAP_0805-10UF,16V,10%,X6S,C95333-007!!
S!C9L10!!DEFAULT_CAPACITOR_1e+07pF_2_1!!CAP!!CAP_0805-10UF,16V,10%,X6S,C95333-007!!
S!C9L13!66!DEFAULT_CAPACITOR_1e+07pF_2_1!!CAP!!CAP_0805-10UF,16V,10%,X6S,C95333-007!!
S!C9L6!65!DEFAULT_CAPACITOR_1e+07pF_2_1!!CAP!!CAP_0805-10UF,16V,10%,X6S,C95333-007!!
S!C9L5!70!DEFAULT_CAPACITOR_1e+07pF_2_1!!CAP!!CAP_0805-10UF,16V,10%,X6S,C95333-007!!
S!C9U6!18!DEFAULT_CAPACITOR_1e+07pF_2_1!!CAP!!CAP_0805-10UF,16V,10%,X6S,C95333-007!!
S!C9T9!24!DEFAULT_CAPACITOR_1e+07pF_2_1!!CAP!!CAP_0805-10UF,16V,10%,X6S,C95333-007!!
S!C9U4!17!DEFAULT_CAPACITOR_1e+07pF_2_1!!CAP!!CAP_0805-10UF,16V,10%,X6S,C95333-007!!
S!C9T6!23!DEFAULT_CAPACITOR_1e+07pF_2_1!!CAP!!CAP_0805-10UF,16V,10%,X6S,C95333-007!!
S!C9T4!16!DEFAULT_CAPACITOR_1e+07pF_2_1!!CAP!!CAP_0805-10UF,16V,10%,X6S,C95333-007!!
S!C9U3!25!DEFAULT_CAPACITOR_1e+07pF_2_1!!CAP!!CAP_0805-10UF,16V,10%,X6S,C95333-007!!
S!C9P26!!DEFAULT_CAPACITOR_1e+07pF_2_1!!CAP!!CAP_0805-10UF,16V,10%,X6S,C95333-007!!
S!C9R11!!DEFAULT_CAPACITOR_1e+07pF_2_1!!CAP!!CAP_0805-10UF,16V,10%,X6S,C95333-007!!
S!C9P25!!DEFAULT_CAPACITOR_1e+07pF_2_1!!CAP!!CAP_0805-10UF,16V,10%,X6S,C95333-007!!
S!C9R10!!DEFAULT_CAPACITOR_1e+07pF_2_1!!CAP!!CAP_0805-10UF,16V,10%,X6S,C95333-007!!
S!C9P22!!DEFAULT_CAPACITOR_1e+07pF_2_1!!CAP!!CAP_0805-10UF,16V,10%,X6S,C95333-007!!
S!C9R7!!DEFAULT_CAPACITOR_1e+07pF_2_1!!CAP!!CAP_0805-10UF,16V,10%,X6S,C95333-007!!
S!C9P9!3!DEFAULT_CAPACITOR_1e+07pF_2_1!!CAP!!CAP_0805-10UF,16V,10%,X6S,C95333-007!!
S!C9P2!!DEFAULT_CAPACITOR_1e+07pF_2_1!!CAP!!CAP_0805-10UF,16V,10%,X6S,C95333-007!!
S!C9P7!1!DEFAULT_CAPACITOR_1e+07pF_2_1!!CAP!!CAP_0805-10UF,16V,10%,X6S,C95333-007!!
S!C9P1!!DEFAULT_CAPACITOR_1e+07pF_2_1!!CAP!!CAP_0805-10UF,16V,10%,X6S,C95333-007!!
S!C9P4!2!DEFAULT_CAPACITOR_1e+07pF_2_1!!CAP!!CAP_0805-10UF,16V,10%,X6S,C95333-007!!
S!C9P24!!DEFAULT_CAPACITOR_1e+07pF_2_1!!CAP!!CAP_0805-10UF,16V,10%,X6S,C95333-007!!
S!C9N21!!DEFAULT_CAPACITOR_1e+07pF_2_1!!CAP!!CAP_0805-10UF,16V,10%,X6S,C95333-007!!
S!C9N19!!DEFAULT_CAPACITOR_1e+07pF_2_1!!CAP!!CAP_0805-10UF,16V,10%,X6S,C95333-007!!
S!C9N13!!DEFAULT_CAPACITOR_1e+07pF_2_1!!CAP!!CAP_0805-10UF,16V,10%,X6S,C95333-007!!
S!C6N11!61!DEFAULT_CAPACITOR_1e+07pF_2_1!!CAP!!CAP_0805-10UF,16V,10%,X6S,C95333-007!!
S!C6N10!33!DEFAULT_CAPACITOR_1e+07pF_2_1!!CAP!!CAP_0805-10UF,16V,10%,X6S,C95333-007!!
S!C1E15!!DEFAULT_CAPACITOR_1e+07pF_2_1!!CAP!!CAP_0805-10UF,16V,10%,X6S,C95333-007!!
S!C3D22!!DEFAULT_CAPACITOR_1e+07pF_2_1!!CAP!!CAP_0805-10UF,16V,10%,X7R,G10601-001!!
S!C1U20!!DEFAULT_CAPACITOR_1e+07pF_2_1!!CAP!!CAP_0805-10UF,16V,10%,X7R,G10601-001!!
S!C6U10!!DEFAULT_CAPACITOR_1e+07pF_2_1!!CAP!!CAP_0805-10UF,16V,10%,X7R,G10601-001!!
S!C6T2!!DEFAULT_CAPACITOR_1e+07pF_2_1!!CAP!!CAP_0805-10UF,16V,10%,X7R,G10601-001!!
S!C6U18!!DEFAULT_CAPACITOR_1e+07pF_2_1!!CAP!!CAP_0805-10UF,16V,10%,X7R,G10601-001!!
S!C4A17!!DEFAULT_CAPACITOR_1e+07pF_2_1!!CAP!!CAP_0805-10UF,16V,10%,X7R,G10601-001!!
S!C4A4!!DEFAULT_CAPACITOR_1e+07pF_2_1!!CAP!!CAP_0805-10UF,16V,10%,X7R,G10601-001!!
S!C4B11!!DEFAULT_CAPACITOR_1e+07pF_2_1!!CAP!!CAP_0805-10UF,16V,10%,X7R,G10601-001!!
S!C9U8!!DEFAULT_CAPACITOR_1e+07pF_2_1!!CAP!!CAP_0805-10UF,16V,10%,X7R,G10601-001!!
S!C9U11!!DEFAULT_CAPACITOR_1e+07pF_2_1!!CAP!!CAP_0805-10UF,16V,10%,X7R,G10601-001!!
S!C9T8!!DEFAULT_CAPACITOR_1e+07pF_2_1!!CAP!!CAP_0805-10UF,16V,10%,X7R,G10601-001!!
S!C1A16!!DEFAULT_CAPACITOR_1e+07pF_2_1!!CAP!!CAP_0805-10UF,16V,10%,X7R,G10601-001!!
S!C1B7!!DEFAULT_CAPACITOR_1e+07pF_2_1!!CAP!!CAP_0805-10UF,16V,10%,X7R,G10601-001!!
S!C1A4!!DEFAULT_CAPACITOR_1e+07pF_2_1!!CAP!!CAP_0805-10UF,16V,10%,X7R,G10601-001!!
S!C2T7!33!DEFAULT_CAPACITOR_4.7e+07pF_2_1!!CAP!!CAP_0805-22UF,6.3V,20%,X6S,C95333-008!!
S!C2T6!33!DEFAULT_CAPACITOR_4.7e+07pF_2_1!!CAP!!CAP_0805-22UF,6.3V,20%,X6S,C95333-008!!
S!C2T9!33!DEFAULT_CAPACITOR_2.2e+07pF_2_1!!CAP!!CAP_0805-22UF,6.3V,20%,X6S,C95333-008!!
S!C8E7!33!DEFAULT_CAPACITOR_2.2e+07pF_2_1!!CAP!!CAP_0805-22UF,6.3V,20%,X6S,C95333-008!!
S!C8E9!49!DEFAULT_CAPACITOR_2.2e+07pF_2_1!!CAP!!CAP_0805-22UF,6.3V,20%,X6S,C95333-008!!
S!C8A14!31!DEFAULT_CAPACITOR_2.2e+07pF_2_1!!CAP!!CAP_0805-22UF,6.3V,20%,X6S,C95333-008!!
S!C2L45!61!DEFAULT_CAPACITOR_2.2e+07pF_2_1!!CAP!!CAP_0805-22UF,6.3V,20%,X6S,C95333-008!!
S!C1T13!!DEFAULT_CAPACITOR_2.2e+07pF_2_1!!CAP!!CAP_0805-22UF,6.3V,20%,X6S,C95333-008!!
S!C1T9!!DEFAULT_CAPACITOR_2.2e+07pF_2_1!!CAP!!CAP_0805-22UF,6.3V,20%,X6S,C95333-008!!
S!C7P3!!DEFAULT_CAPACITOR_2.2e+07pF_2_1!!CAP!!CAP_0805-47UF,4V,20%,X6S,C95333-006!!
S!C7P18!!DEFAULT_CAPACITOR_2.2e+07pF_2_1!!CAP!!CAP_0805-47UF,4V,20%,X6S,C95333-006!!
S!C7P17!!DEFAULT_CAPACITOR_2.2e+07pF_2_1!!CAP!!CAP_0805-47UF,4V,20%,X6S,C95333-006!!
S!C5P21!155!DEFAULT_CAPACITOR_2.2e+07pF_2_1!!CAP!!CAP_0805-47UF,4V,20%,X6S,C95333-006!!
S!C5P44!156!DEFAULT_CAPACITOR_2.2e+07pF_2_1!!CAP!!CAP_0805-47UF,4V,20%,X6S,C95333-006!!
S!C5P43!157!DEFAULT_CAPACITOR_2.2e+07pF_2_1!!CAP!!CAP_0805-47UF,4V,20%,X6S,C95333-006!!
S!C5P42!191!DEFAULT_CAPACITOR_2.2e+07pF_2_1!!CAP!!CAP_0805-47UF,4V,20%,X6S,C95333-006!!
S!C5P40!173!DEFAULT_CAPACITOR_2.2e+07pF_2_1!!CAP!!CAP_0805-47UF,4V,20%,X6S,C95333-006!!
S!C5P41!99!DEFAULT_CAPACITOR_2.2e+07pF_2_1!!CAP!!CAP_0805-47UF,4V,20%,X6S,C95333-006!!
S!C5P27!119!DEFAULT_CAPACITOR_2.2e+07pF_2_1!!CAP!!CAP_0805-47UF,4V,20%,X6S,C95333-006!!
S!C5P26!120!DEFAULT_CAPACITOR_2.2e+07pF_2_1!!CAP!!CAP_0805-47UF,4V,20%,X6S,C95333-006!!
S!C5P6!100!DEFAULT_CAPACITOR_2.2e+07pF_2_1!!CAP!!CAP_0805-47UF,4V,20%,X6S,C95333-006!!
S!C5P5!121!DEFAULT_CAPACITOR_2.2e+07pF_2_1!!CAP!!CAP_0805-47UF,4V,20%,X6S,C95333-006!!
S!C5P4!122!DEFAULT_CAPACITOR_2.2e+07pF_2_1!!CAP!!CAP_0805-47UF,4V,20%,X6S,C95333-006!!
S!C5P17!101!DEFAULT_CAPACITOR_2.2e+07pF_2_1!!CAP!!CAP_0805-47UF,4V,20%,X6S,C95333-006!!
S!C5P3!194!DEFAULT_CAPACITOR_2.2e+07pF_2_1!!CAP!!CAP_0805-47UF,4V,20%,X6S,C95333-006!!
S!C5P16!123!DEFAULT_CAPACITOR_2.2e+07pF_2_1!!CAP!!CAP_0805-47UF,4V,20%,X6S,C95333-006!!
S!C5P15!102!DEFAULT_CAPACITOR_2.2e+07pF_2_1!!CAP!!CAP_0805-47UF,4V,20%,X6S,C95333-006!!
S!C4P4!211!DEFAULT_CAPACITOR_2.2e+07pF_2_1!!CAP!!CAP_0805-47UF,4V,20%,X6S,C95333-006!!
S!C5P18!212!DEFAULT_CAPACITOR_2.2e+07pF_2_1!!CAP!!CAP_0805-47UF,4V,20%,X6S,C95333-006!!
S!C5P22!174!DEFAULT_CAPACITOR_2.2e+07pF_2_1!!CAP!!CAP_0805-47UF,4V,20%,X6S,C95333-006!!
S!C5P23!105!DEFAULT_CAPACITOR_2.2e+07pF_2_1!!CAP!!CAP_0805-47UF,4V,20%,X6S,C95333-006!!
S!C5P24!124!DEFAULT_CAPACITOR_2.2e+07pF_2_1!!CAP!!CAP_0805-47UF,4V,20%,X6S,C95333-006!!
S!C5P25!196!DEFAULT_CAPACITOR_2.2e+07pF_2_1!!CAP!!CAP_0805-47UF,4V,20%,X6S,C95333-006!!
S!C5P19!213!DEFAULT_CAPACITOR_2.2e+07pF_2_1!!CAP!!CAP_0805-47UF,4V,20%,X6S,C95333-006!!
S!C4P7!214!DEFAULT_CAPACITOR_2.2e+07pF_2_1!!CAP!!CAP_0805-47UF,4V,20%,X6S,C95333-006!!
S!C4P3!126!DEFAULT_CAPACITOR_2.2e+07pF_2_1!!CAP!!CAP_0805-47UF,4V,20%,X6S,C95333-006!!
S!C5P10!215!DEFAULT_CAPACITOR_2.2e+07pF_2_1!!CAP!!CAP_0805-47UF,4V,20%,X6S,C95333-006!!
S!C5P11!197!DEFAULT_CAPACITOR_2.2e+07pF_2_1!!CAP!!CAP_0805-47UF,4V,20%,X6S,C95333-006!!
S!C5P28!216!DEFAULT_CAPACITOR_2.2e+07pF_2_1!!CAP!!CAP_0805-47UF,4V,20%,X6S,C95333-006!!
S!C8P11!!DEFAULT_CAPACITOR_2.2e+07pF_2_1!!CAP!!CAP_0805-47UF,4V,20%,X6S,C95333-006!!
S!C8P9!!DEFAULT_CAPACITOR_2.2e+07pF_2_1!!CAP!!CAP_0805-47UF,4V,20%,X6S,C95333-006!!
S!C8P29!!DEFAULT_CAPACITOR_2.2e+07pF_2_1!!CAP!!CAP_0805-47UF,4V,20%,X6S,C95333-006!!
S!C8P28!!DEFAULT_CAPACITOR_2.2e+07pF_2_1!!CAP!!CAP_0805-47UF,4V,20%,X6S,C95333-006!!
S!C8P27!!DEFAULT_CAPACITOR_2.2e+07pF_2_1!!CAP!!CAP_0805-47UF,4V,20%,X6S,C95333-006!!
S!C8P26!!DEFAULT_CAPACITOR_2.2e+07pF_2_1!!CAP!!CAP_0805-47UF,4V,20%,X6S,C95333-006!!
S!C8P13!!DEFAULT_CAPACITOR_2.2e+07pF_2_1!!CAP!!CAP_0805-47UF,4V,20%,X6S,C95333-006!!
S!C8P25!!DEFAULT_CAPACITOR_2.2e+07pF_2_1!!CAP!!CAP_0805-47UF,4V,20%,X6S,C95333-006!!
S!C8P15!!DEFAULT_CAPACITOR_2.2e+07pF_2_1!!CAP!!CAP_0805-47UF,4V,20%,X6S,C95333-006!!
S!C8P33!!DEFAULT_CAPACITOR_2.2e+07pF_2_1!!CAP!!CAP_0805-47UF,4V,20%,X6S,C95333-006!!
S!C8P21!!DEFAULT_CAPACITOR_2.2e+07pF_2_1!!CAP!!CAP_0805-47UF,4V,20%,X6S,C95333-006!!
S!C8P8!!DEFAULT_CAPACITOR_2.2e+07pF_2_1!!CAP!!CAP_0805-47UF,4V,20%,X6S,C95333-006!!
S!C8P16!!DEFAULT_CAPACITOR_2.2e+07pF_2_1!!CAP!!CAP_0805-47UF,4V,20%,X6S,C95333-006!!
S!C8P17!!DEFAULT_CAPACITOR_2.2e+07pF_2_1!!CAP!!CAP_0805-47UF,4V,20%,X6S,C95333-006!!
S!C8P18!!DEFAULT_CAPACITOR_2.2e+07pF_2_1!!CAP!!CAP_0805-47UF,4V,20%,X6S,C95333-006!!
S!C8P19!!DEFAULT_CAPACITOR_2.2e+07pF_2_1!!CAP!!CAP_0805-47UF,4V,20%,X6S,C95333-006!!
S!C8P12!!DEFAULT_CAPACITOR_2.2e+07pF_2_1!!CAP!!CAP_0805-47UF,4V,20%,X6S,C95333-006!!
S!C8P20!!DEFAULT_CAPACITOR_2.2e+07pF_2_1!!CAP!!CAP_0805-47UF,4V,20%,X6S,C95333-006!!
S!C8P3!!DEFAULT_CAPACITOR_2.2e+07pF_2_1!!CAP!!CAP_0805-47UF,4V,20%,X6S,C95333-006!!
S!C8P34!!DEFAULT_CAPACITOR_2.2e+07pF_2_1!!CAP!!CAP_0805-47UF,4V,20%,X6S,C95333-006!!
S!C8P4!!DEFAULT_CAPACITOR_2.2e+07pF_2_1!!CAP!!CAP_0805-47UF,4V,20%,X6S,C95333-006!!
S!C7P2!!DEFAULT_CAPACITOR_2.2e+07pF_2_1!!CAP!!CAP_0805-47UF,4V,20%,X6S,C95333-006!!
S!C7P1!!DEFAULT_CAPACITOR_2.2e+07pF_2_1!!CAP!!CAP_0805-47UF,4V,20%,X6S,C95333-006!!
S!C8P24!!DEFAULT_CAPACITOR_2.2e+07pF_2_1!!CAP!!CAP_0805-47UF,4V,20%,X6S,C95333-006!!
S!C7P19!!DEFAULT_CAPACITOR_2.2e+07pF_2_1!!CAP!!CAP_0805-47UF,4V,20%,X6S,C95333-006!!
S!C7P20!!DEFAULT_CAPACITOR_2.2e+07pF_2_1!!CAP!!CAP_0805-47UF,4V,20%,X6S,C95333-006!!
S!C8P32!!DEFAULT_CAPACITOR_2.2e+07pF_2_1!!CAP!!CAP_0805-47UF,4V,20%,X6S,C95333-006!!
S!C8P14!!DEFAULT_CAPACITOR_2.2e+07pF_2_1!!CAP!!CAP_0805-47UF,4V,20%,X6S,C95333-006!!
S!C7P14!!DEFAULT_CAPACITOR_2.2e+07pF_2_1!!CAP!!CAP_0805-47UF,4V,20%,X6S,C95333-006!!
S!C8P23!!DEFAULT_CAPACITOR_2.2e+07pF_2_1!!CAP!!CAP_0805-47UF,4V,20%,X6S,C95333-006!!
S!C7P15!!DEFAULT_CAPACITOR_2.2e+07pF_2_1!!CAP!!CAP_0805-47UF,4V,20%,X6S,C95333-006!!
S!C8P22!!DEFAULT_CAPACITOR_2.2e+07pF_2_1!!CAP!!CAP_0805-47UF,4V,20%,X6S,C95333-006!!
S!C7P7!!DEFAULT_CAPACITOR_2.2e+07pF_2_1!!CAP!!CAP_0805-47UF,4V,20%,X6S,C95333-006!!
S!C7P10!!DEFAULT_CAPACITOR_2.2e+07pF_2_1!!CAP!!CAP_0805-47UF,4V,20%,X6S,C95333-006!!
S!C7P13!!DEFAULT_CAPACITOR_2.2e+07pF_2_1!!CAP!!CAP_0805-47UF,4V,20%,X6S,C95333-006!!
S!C7P6!!DEFAULT_CAPACITOR_2.2e+07pF_2_1!!CAP!!CAP_0805-47UF,4V,20%,X6S,C95333-006!!
S!C7P9!!DEFAULT_CAPACITOR_4.7e+07pF_2_1!!CAP!!CAP_0805-47UF,4V,20%,X6S,C95333-006!!
S!C7P5!!DEFAULT_CAPACITOR_4.7e+07pF_2_1!!CAP!!CAP_0805-47UF,4V,20%,X6S,C95333-006!!
S!C7P11!!DEFAULT_CAPACITOR_4.7e+07pF_2_1!!CAP!!CAP_0805-47UF,4V,20%,X6S,C95333-006!!
S!C7P8!!DEFAULT_CAPACITOR_4.7e+07pF_2_1!!CAP!!CAP_0805-47UF,4V,20%,X6S,C95333-006!!
S!C7P4!!DEFAULT_CAPACITOR_4.7e+07pF_2_1!!CAP!!CAP_0805-47UF,4V,20%,X6S,C95333-006!!
S!C5P29!!DEFAULT_CAPACITOR_4.7e+07pF_2_1!!CAP!!CAP_0805-47UF,4V,20%,X6S,C95333-006!!
S!C5P30!!DEFAULT_CAPACITOR_4.7e+07pF_2_1!!CAP!!CAP_0805-47UF,4V,20%,X6S,C95333-006!!
S!C5P31!!DEFAULT_CAPACITOR_4.7e+07pF_2_1!!CAP!!CAP_0805-47UF,4V,20%,X6S,C95333-006!!
S!C4P2!!DEFAULT_CAPACITOR_4.7e+07pF_2_1!!CAP!!CAP_0805-47UF,4V,20%,X6S,C95333-006!!
S!C4P5!!DEFAULT_CAPACITOR_4.7e+07pF_2_1!!CAP!!CAP_0805-47UF,4V,20%,X6S,C95333-006!!
S!C5P37!210!DEFAULT_CAPACITOR_2.2e+07pF_2_1!!CAP!!CAP_0805-47UF,4V,20%,X6S,C95333-006!!
S!C5P36!154!DEFAULT_CAPACITOR_2.2e+07pF_2_1!!CAP!!CAP_0805-47UF,4V,20%,X6S,C95333-006!!
S!C5P35!188!DEFAULT_CAPACITOR_2.2e+07pF_2_1!!CAP!!CAP_0805-47UF,4V,20%,X6S,C95333-006!!
S!C5P34!165!DEFAULT_CAPACITOR_2.2e+07pF_2_1!!CAP!!CAP_0805-47UF,4V,20%,X6S,C95333-006!!
S!C5P33!189!DEFAULT_CAPACITOR_2.2e+07pF_2_1!!CAP!!CAP_0805-47UF,4V,20%,X6S,C95333-006!!
S!C5P32!171!DEFAULT_CAPACITOR_2.2e+07pF_2_1!!CAP!!CAP_0805-47UF,4V,20%,X6S,C95333-006!!
S!C5P20!190!DEFAULT_CAPACITOR_2.2e+07pF_2_1!!CAP!!CAP_0805-47UF,4V,20%,X6S,C95333-006!!
S!C5P13!172!DEFAULT_CAPACITOR_2.2e+07pF_2_1!!CAP!!CAP_0805-47UF,4V,20%,X6S,C95333-006!!
S!C5P14!192!DEFAULT_CAPACITOR_2.2e+07pF_2_1!!CAP!!CAP_0805-47UF,4V,20%,X6S,C95333-006!!
S!C5P12!193!DEFAULT_CAPACITOR_2.2e+07pF_2_1!!CAP!!CAP_0805-47UF,4V,20%,X6S,C95333-006!!
S!C4P10!134!DEFAULT_CAPACITOR_2.2e+07pF_2_1!!CAP!!CAP_0805-47UF,4V,20%,X6S,C95333-006!!
S!C4P9!136!DEFAULT_CAPACITOR_2.2e+07pF_2_1!!CAP!!CAP_0805-47UF,4V,20%,X6S,C95333-006!!
S!C4P1!153!DEFAULT_CAPACITOR_2.2e+07pF_2_1!!CAP!!CAP_0805-47UF,4V,20%,X6S,C95333-006!!
S!C8P10!!DEFAULT_CAPACITOR_2.2e+07pF_2_1!!CAP!!CAP_0805-47UF,4V,20%,X6S,C95333-006!!
S!C8A12!72!DEFAULT_CAPACITOR_4.7e+07pF_2_1!!CAP!!CAP_0805-47UF,4V,20%,X6S,C95333-006!!
S!C2L32!71!DEFAULT_CAPACITOR_4.7e+07pF_2_1!!CAP!!CAP_0805-47UF,4V,20%,X6S,C95333-006!!
S!C6B3!33!DEFAULT_CAPACITOR_4.7e+07pF_2_1!!CAP!!CAP_0805-47UF,4V,20%,X6S,C95333-006!!
S!C7B7!33!DEFAULT_CAPACITOR_4.7e+07pF_2_1!!CAP!!CAP_0805-47UF,4V,20%,X6S,C95333-006!!
S!C6U3!33!DEFAULT_CAPACITOR_4.7e+07pF_2_1!!CAP!!CAP_0805-47UF,4V,20%,X6S,C95333-006!!
S!C6U2!33!DEFAULT_CAPACITOR_4.7e+07pF_2_1!!CAP!!CAP_0805-47UF,4V,20%,X6S,C95333-006!!
S!C4B3!33!DEFAULT_CAPACITOR_4.7e+07pF_2_1!!CAP!!CAP_0805-47UF,4V,20%,X6S,C95333-006!!
S!C4B2!33!DEFAULT_CAPACITOR_4.7e+07pF_2_1!!CAP!!CAP_0805-47UF,4V,20%,X6S,C95333-006!!
S!C3T7!33!DEFAULT_CAPACITOR_4.7e+07pF_2_1!!CAP!!CAP_0805-47UF,4V,20%,X6S,C95333-006!!
S!C3T9!33!DEFAULT_CAPACITOR_4.7e+07pF_2_1!!CAP!!CAP_0805-47UF,4V,20%,X6S,C95333-006!!
S!C7A31!!DEFAULT_CAPACITOR_4.7e+07pF_2_1!!CAP!!CAP_0805-47UF,4V,20%,X6S,C95333-006!!
S!C7A32!!DEFAULT_CAPACITOR_4.7e+07pF_2_1!!CAP!!CAP_0805-47UF,4V,20%,X6S,C95333-006!!
S!C7B4!!DEFAULT_CAPACITOR_4.7e+07pF_2_1!!CAP!!CAP_0805-47UF,4V,20%,X6S,C95333-006!!
S!C7A33!!DEFAULT_CAPACITOR_4.7e+07pF_2_1!!CAP!!CAP_0805-47UF,4V,20%,X6S,C95333-006!!
S!C8B15!!DEFAULT_CAPACITOR_4.7e+07pF_2_1!!CAP!!CAP_0805-47UF,4V,20%,X6S,C95333-006!!
S!C8B16!!DEFAULT_CAPACITOR_4.7e+07pF_2_1!!CAP!!CAP_0805-47UF,4V,20%,X6S,C95333-006!!
S!C8A13!!DEFAULT_CAPACITOR_4.7e+07pF_2_1!!CAP!!CAP_0805-47UF,4V,20%,X6S,C95333-006!!
S!C2M11!!DEFAULT_CAPACITOR_4.7e+07pF_2_1!!CAP!!CAP_0805-47UF,4V,20%,X6S,C95333-006!!
S!C2M17!!DEFAULT_CAPACITOR_4.7e+07pF_2_1!!CAP!!CAP_0805-47UF,4V,20%,X6S,C95333-006!!
S!C7A30!!DEFAULT_CAPACITOR_2.2e+07pF_2_1!!CAP!!CAP_0805LF-22UF,4V,20%,X6S,C95333-002!!
S!C8A16!23!DEFAULT_CAPACITOR_2.2e+07pF_2_1!!CAP!!CAP_0805LF-22UF,4V,20%,X6S,C95333-002!!
S!C5P39!!DEFAULT_CAPACITOR_2.2e+07pF_2_1!!CAP!!CAP_0805LF-22UF,4V,20%,X6S,C95333-002!!
S!C5P38!!DEFAULT_CAPACITOR_2.2e+07pF_2_1!!CAP!!CAP_0805LF-22UF,4V,20%,X6S,C95333-002!!
S!C5P2!!DEFAULT_CAPACITOR_2.2e+07pF_2_1!!CAP!!CAP_0805LF-22UF,4V,20%,X6S,C95333-002!!
S!C5P1!!DEFAULT_CAPACITOR_2.2e+07pF_2_1!!CAP!!CAP_0805LF-22UF,4V,20%,X6S,C95333-002!!
S!C8P30!!DEFAULT_CAPACITOR_2.2e+07pF_2_1!!CAP!!CAP_0805LF-22UF,4V,20%,X6S,C95333-002!!
S!C8P31!!DEFAULT_CAPACITOR_2.2e+07pF_2_1!!CAP!!CAP_0805LF-22UF,4V,20%,X6S,C95333-002!!
S!C8P2!!DEFAULT_CAPACITOR_2.2e+07pF_2_1!!CAP!!CAP_0805LF-22UF,4V,20%,X6S,C95333-002!!
S!C8P1!!DEFAULT_CAPACITOR_2.2e+07pF_2_1!!CAP!!CAP_0805LF-22UF,4V,20%,X6S,C95333-002!!
S!C4G24!19!DEFAULT_CAPACITOR_2.2e+07pF_2_1!!CAP!!CAP_0805LF-22UF,4V,20%,X6S,C95333-002!!
S!C4G20!!DEFAULT_CAPACITOR_2.2e+07pF_2_1!!CAP!!CAP_0805LF-22UF,4V,20%,X6S,C95333-002!!
S!C4A1!!DEFAULT_CAPACITOR_2.2e+07pF_2_1!!CAP!!CAP_0805LF-22UF,4V,20%,X6S,C95333-002!!
S!C4A13!!DEFAULT_CAPACITOR_2.2e+07pF_2_1!!CAP!!CAP_0805LF-22UF,4V,20%,X6S,C95333-002!!
S!C9F4!!DEFAULT_CAPACITOR_2.2e+07pF_2_1!!CAP!!CAP_0805LF-22UF,4V,20%,X6S,C95333-002!!
S!C9F13!!DEFAULT_CAPACITOR_2.2e+07pF_2_1!!CAP!!CAP_0805LF-22UF,4V,20%,X6S,C95333-002!!
S!C6G3!8!DEFAULT_CAPACITOR_2.2e+07pF_2_1!!CAP!!CAP_0805LF-22UF,4V,20%,X6S,C95333-002!!
S!C7G27!4!DEFAULT_CAPACITOR_2.2e+07pF_2_1!!CAP!!CAP_0805LF-22UF,4V,20%,X6S,C95333-002!!
S!C5P7!103!DEFAULT_CAPACITOR_2.2e+07pF_2_1!!CAP!!CAP_0805LF-22UF,4V,20%,X6S,C95333-002!!
S!C1G17!!DEFAULT_CAPACITOR_2.2e+07pF_2_1!!CAP!!CAP_0805LF-22UF,4V,20%,X6S,C95333-002!!
S!C6A1!3!DEFAULT_CAPACITOR_2.2e+07pF_2_1!!CAP!!CAP_0805LF-22UF,4V,20%,X6S,C95333-002!!
S!C6A4!!DEFAULT_CAPACITOR_2.2e+07pF_2_1!!CAP!!CAP_0805LF-22UF,4V,20%,X6S,C95333-002!!
S!C1A1!54!DEFAULT_CAPACITOR_2.2e+07pF_2_1!!CAP!!CAP_0805LF-22UF,4V,20%,X6S,C95333-002!!
S!C1G20!!DEFAULT_CAPACITOR_2.2e+07pF_2_1!!CAP!!CAP_0805LF-22UF,4V,20%,X6S,C95333-002!!
S!C1A12!53!DEFAULT_CAPACITOR_2.2e+07pF_2_1!!CAP!!CAP_0805LF-22UF,4V,20%,X6S,C95333-002!!
S!C5P8!183!DEFAULT_CAPACITOR_2.2e+07pF_2_1!!CAP!!CAP_0805LF-22UF,4V,20%,X6S,C95333-002!!
S!C5P9!184!DEFAULT_CAPACITOR_2.2e+07pF_2_1!!CAP!!CAP_0805LF-22UF,4V,20%,X6S,C95333-002!!
S!C8P5!!DEFAULT_CAPACITOR_2.2e+07pF_2_1!!CAP!!CAP_0805LF-22UF,4V,20%,X6S,C95333-002!!
S!C8P6!!DEFAULT_CAPACITOR_2.2e+07pF_2_1!!CAP!!CAP_0805LF-22UF,4V,20%,X6S,C95333-002!!
S!C8P7!!DEFAULT_CAPACITOR_2.2e+07pF_2_1!!CAP!!CAP_0805LF-22UF,4V,20%,X6S,C95333-002!!
S!C7B8!!DEFAULT_CAPACITOR_4.7e+07pF_2_1!!CAP!!CAP_1210-47UF,16V,20%,X6S,D38464-007!!
S!C4G5!!DEFAULT_CAPACITOR_4.7e+07pF_2_1!!CAP!!CAP_1210-47UF,16V,20%,X6S,D38464-007!!
S!C4B1!!DEFAULT_CAPACITOR_4.7e+07pF_2_1!!CAP!!CAP_1210-47UF,16V,20%,X6S,D38464-007!!
S!C7F7!!DEFAULT_CAPACITOR_4.7e+07pF_2_1!!CAP!!CAP_1210-47UF,16V,20%,X6S,D38464-007!!
S!C9F1!!DEFAULT_CAPACITOR_4.7e+07pF_2_1!!CAP!!CAP_1210-47UF,16V,20%,X6S,D38464-007!!
S!C8E11!!DEFAULT_CAPACITOR_4.7e+07pF_2_1!!CAP!!CAP_1210-47UF,16V,20%,X6S,D38464-007!!
S!C1G15!!DEFAULT_CAPACITOR_4.7e+07pF_2_1!!CAP!!CAP_1210-47UF,16V,20%,X6S,D38464-007!!
S!C1G12!!DEFAULT_CAPACITOR_4.7e+07pF_2_1!!CAP!!CAP_1210-47UF,16V,20%,X6S,D38464-007!!
S!C1G2!!DEFAULT_CAPACITOR_4.7e+07pF_2_1!!CAP!!CAP_1210-47UF,16V,20%,X6S,D38464-007!!
S!C1G7!!DEFAULT_CAPACITOR_4.7e+07pF_2_1!!CAP!!CAP_1210-47UF,16V,20%,X6S,D38464-007!!
S!C7E12!44!DEFAULT_CAPACITOR_4.7e+07pF_2_1!!CAP!!CAP_1210-47UF,16V,20%,X6S,D38464-007!!
S!C7E13!37!DEFAULT_CAPACITOR_4.7e+07pF_2_1!!CAP!!CAP_1210-47UF,16V,20%,X6S,D38464-007!!
S!L1M2!!!!CHOKE_4PIN!!CHOKE_4PIN_SMLF-90 OHM,EMPTY,752402-015!!
S!CR2U1!!!!DIODE2A_DUAL!!DIODE2A_DUAL_SMLF-BAS70-05,DIO,C90169-001!!
S!CR1M2!!!!DIODEAC_DUAL_ARRAY!!DIODEAC_DUAL_ARRAY_SM9-ESD3V3U4ULC,IC,G18435-001!!
S!CR1M1!!!!DIODEAC_DUAL_ARRAY!!DIODEAC_DUAL_ARRAY_SM9-ESD3V3U4ULC,IC,G18435-001!!
S!FB7B1!!DEFAULT_RESISTOR_22.000000OHM_2_1!!FERRITE!!FERRITE_SM-22,FB,656554-051!!
S!FB4G1!!DEFAULT_RESISTOR_22.000000OHM_2_1!!FERRITE!!FERRITE_SM-22,FB,656554-051!!
S!FB4A1!!DEFAULT_RESISTOR_22.000000OHM_2_1!!FERRITE!!FERRITE_SM-22,FB,656554-051!!
S!FB7F1!!DEFAULT_RESISTOR_22.000000OHM_2_1!!FERRITE!!FERRITE_SM-22,FB,656554-051!!
S!FB9E1!!DEFAULT_RESISTOR_22.000000OHM_2_1!!FERRITE!!FERRITE_SM-22,FB,656554-051!!
S!FB7E1!!DEFAULT_RESISTOR_22.000000OHM_2_1!!FERRITE!!FERRITE_SM-22,FB,656554-051!!
S!FB1U4!!DEFAULT_RESISTOR_30.000000OHM_2_1!!FERRITE!!FERRITE_SMLF-30,FB,693286-021!!
S!FB1U3!!DEFAULT_RESISTOR_30.000000OHM_2_1!!FERRITE!!FERRITE_SMLF-30,FB,693286-021!!
S!Q4C1!!!!FET_N_DUAL!!FET_N_DUAL_SMLF-NTJD4001N,FET,E40049-001!!
S!Q9G1!!!!FET_N_DUAL!!FET_N_DUAL_SMLF-NTJD4001N,FET,E40049-001!!
S!Q1L2!!!!FET_N_DUAL!!FET_N_DUAL_SMLF-NTJD4001N,FET,E40049-001!!
S!Q9F1!!!!FET_N_DUAL!!FET_N_DUAL_SMLF-NTJD4001N,FET,E40049-001!!
S!Q9A2!!!!FET_N_DUAL!!FET_N_DUAL_SMLF-NTJD4001N,FET,E40049-001!!
S!Q9E1!!!!FET_N_DUAL!!FET_N_DUAL_SMLF-NTJD4001N,FET,E40049-001!!
S!Q7E5!3!!!FET_N_DUAL!!FET_N_DUAL_SMLF-NTJD4001N,FET,E40049-001!!
S!Q7E6!1!!!FET_N_DUAL!!FET_N_DUAL_SMLF-NTJD4001N,FET,E40049-001!!
S!Q4B2!!!!FET_N_DUAL!!FET_N_DUAL_SMLF-NTJD4001N,FET,E40049-001!!
S!Q4U1!!!!FET_N_DUAL!!FET_N_DUAL_SMLF-NTJD4001N,FET,E40049-001!!
S!Q2U1!1!!!FET_N_DUAL!!FET_N_DUAL_SMLF-NTJD4001N,FET,E40049-001!!
S!Q3U1!!!!FET_N_DUAL!!FET_N_DUAL_SMLF-NTJD4001N,FET,E40049-001!!
S!Q7E1!!!!FET_N_DUAL!!FET_N_DUAL_SMLF-NTJD4001N,FET,E40049-001!!
S!Q7E2!!!!FET_N_DUAL!!FET_N_DUAL_SMLF-NTJD4001N,FET,E40049-001!!
S!Q4B1!!!!FET_N_DUAL!!FET_N_DUAL_SMLF-NTJD4001N,FET,E40049-001!!
S!Q7E3!!!!FET_N_DUAL!!FET_N_DUAL_SMLF-NTJD4001N,FET,E40049-001!!
S!Q8E2!!!!FET_N!!FET_N_SOT23LF-2N7002,FET,C79254-001!!
S!Q1D2!!!!FET_N!!FET_N_SOT23LF-2N7002,FET,C79254-001!!
S!Q8E1!!!!FET_N!!FET_N_SOT23LF-2N7002,FET,C79254-001!!
S!Q2P1!!!!FET_N!!FET_N_SOT23LF-2N7002,FET,C79254-001!!
S!Q8F2!!!!FET_N!!FET_N_SOT23LF-2N7002,FET,C79254-001!!
S!Q2T2!!!!FET_N!!FET_N_SOT23LF-2N7002,FET,C79254-001!!
S!Q9A3!!!!FET_N!!FET_N_SOT23LF-2N7002,FET,C79254-001!!
S!Q8F1!!!!FET_N!!FET_N_SOT23LF-2N7002,FET,C79254-001!!
S!U9G1!!!!GTL2014!!GTL2014_SM-IC,D66151-001!!
S!U2T4!!!!GTL2014!!GTL2014_SM-IC,D66151-001!!
S!U3P1!9!!!GTL2014!!GTL2014_SM-IC,D66151-001!!
S!U4C2!!!!GTL2014!!GTL2014_SM-IC,D66151-001!!
S!U3P2!22!!!GTL2014!!GTL2014_SM-IC,D66151-001!!
S!U7D2!9!!!GTL2014!!GTL2014_SM-IC,D66151-001!!
S!DS9A6!!!!LED!!LED_A1LF-GREEN,IC,C97278-010!!
S!DS9A5!!!!LED!!LED_A1LF-GREEN,IC,C97278-010!!
S!DS9E1!!!!LED!!LED_A1LF-GREEN,IC,C97278-010!!
S!EU1E3!!!!MOSFETN_1D3S!!MOSFETN_1D3S_SOT5-IC,G68777-001!!
S!EU9R1!!!!MOSFETN_1D3S!!MOSFETN_1D3S_SOT5-IC,G68777-001!!
S!EU1E1!!!!MOSFETN_1D3S!!MOSFETN_1D3S_SOT5-IC,G68777-001!!
S!R2R9!!DEFAULT_RESISTOR_200.000000OHM_2_1!!RES!!RES_0402-200.0,1%,1/16W,CHIP,G21796-004!!
S!R2T19!!DEFAULT_RESISTOR_200.000000OHM_2_1!!RES!!RES_0402-200.0,1%,1/16W,CHIP,G21796-004!!
S!R2T26!!DEFAULT_RESISTOR_200.000000OHM_2_1!!RES!!RES_0402-200.0,1%,1/16W,CHIP,G21796-004!!
S!R1L31!!DEFAULT_RESISTOR_200.000000OHM_2_1!!RES!!RES_0402-200.0,1%,1/16W,CHIP,G21796-004!!
S!R1L22!!DEFAULT_RESISTOR_200.000000OHM_2_1!!RES!!RES_0402-200.0,1%,1/16W,CHIP,G21796-004!!
S!R2T13!!DEFAULT_RESISTOR_200.000000OHM_2_1!!RES!!RES_0402-200.0,1%,1/16W,CHIP,G21796-004!!
S!R9E12!!DEFAULT_RESISTOR_200.000000OHM_2_1!!RES!!RES_0402-200.0,1%,1/16W,CHIP,G21796-004!!
S!R9E11!!DEFAULT_RESISTOR_200.000000OHM_2_1!!RES!!RES_0402-200.0,1%,1/16W,CHIP,G21796-004!!
S!R9E10!!DEFAULT_RESISTOR_200.000000OHM_2_1!!RES!!RES_0402-200.0,1%,1/16W,CHIP,G21796-004!!
S!R2T37!!DEFAULT_RESISTOR_200.000000OHM_2_1!!RES!!RES_0402-200.0,1%,1/16W,CHIP,G21796-004!!
S!R1M14!!DEFAULT_RESISTOR_200.000000OHM_2_1!!RES!!RES_0402-200.0,1%,1/16W,CHIP,G21796-004!!
S!R1B20!!DEFAULT_RESISTOR_0.001OHM_2_1!!RES!!RES_2010-0.001,1%,1W,CHIP,E30969-002!!
S!R4C6!!DEFAULT_RESISTOR_0.001OHM_2_1!!RES!!RES_2010-0.001,1%,1W,CHIP,E30969-002!!
S!R1D49!!!!RES_PWR!!RES_PWR_6PAD-0.001,1%,3W,CHIP,E74391-005!!
S!R9R1!!!!RES_PWR!!RES_PWR_6PAD-0.001,1%,3W,CHIP,E74391-005!!
